FILE_TYPE = MACRO_DRAWING;
SET COLOR_WIRE YELLOW;
SET COLOR_PROP ORANGE;
SET COLOR_DOT WHITE;
SET COLOR_ARC YELLOW;
SET COLOR_BODY GREEN;
SET COLOR_NOTE PURPLE;
SET PROP_DISPLAY VALUE;
SET PAGE_NUMBER P55;
FORCEADD Q_RES..1
(-5525 1050);
FORCEPROP 1 LAST LOCATION R571
J 0
(-5575 1100);
DISPLAY 0.489362 (-5575 1100);
PAINT SKYBLUE (-5575 1100);
FORCEPROP 0 LAST $SEC 1
J 0
(-5575 1200);
DISPLAY 0.680851 (-5575 1200);
PAINT MONO (-5575 1200);
DISPLAY INVISIBLE (-5575 1200);
FORCEPROP 0 LAST CDS_SEC 1
J 0
(-5575 1200);
DISPLAY 1.021277 (-5575 1200);
DISPLAY INVISIBLE (-5575 1200);
FORCEPROP 1 LASTPIN (-5625 1050) $PN 1
J 0
(-5613 1062);
DISPLAY 0.489362 (-5613 1062);
PAINT MONO (-5613 1062);
FORCEPROP 1 LASTPIN (-5425 1050) $PN 2
J 0
(-5463 1062);
DISPLAY 0.489362 (-5463 1062);
PAINT MONO (-5463 1062);
FORCEPROP 1 LAST PACK_TYPE 0402LF
J 0
(-5275 900);
DISPLAY 0.489362 (-5275 900);
PAINT SKYBLUE (-5275 900);
FORCEPROP 1 LAST PART_NUMBER CS61002JB23
J 0
(-5750 1150);
DISPLAY 0.489362 (-5750 1150);
PAINT SKYBLUE (-5750 1150);
FORCEPROP 1 LAST VALUE 10M
J 2
(-5550 950);
DISPLAY 0.489362 (-5550 950);
PAINT SKYBLUE (-5550 950);
FORCEPROP 1 LAST TOLERANCE 5%
J 0
(-5525 950);
DISPLAY 0.489362 (-5525 950);
PAINT SKYBLUE (-5525 950);
FORCEPROP 1 LAST MATERIAL CHIP
J 0
(-5525 900);
DISPLAY 0.489362 (-5525 900);
PAINT SKYBLUE (-5525 900);
FORCEPROP 1 LAST WATTAGE 1/16W
J 2
(-5550 900);
DISPLAY 0.489362 (-5550 900);
PAINT SKYBLUE (-5550 900);
FORCEPROP 1 LAST PATH I10
J 0
(-5575 1200);
DISPLAY 0.978723 (-5575 1200);
PAINT WHITE (-5575 1200);
DISPLAY INVISIBLE (-5575 1200);
FORCEPROP 2 LAST CDS_LIB pure_quanta
J 0
(-5525 1050);
DISPLAY INVISIBLE (-5525 1050);
FORCEADD UNIVERSAL_GND..1
(-5900 1250);
FORCEPROP 3 LASTPIN (-5900 1300) SIG_NAME GND\g
J 0
(-5890 1310);
DISPLAY 0.659574 (-5890 1310);
PAINT MONO (-5890 1310);
DISPLAY INVISIBLE (-5890 1310);
FORCEPROP 1 LAST HDL_POWER GND
J 1
(-5875 1175);
DISPLAY 0.872340 (-5875 1175);
PAINT GREEN (-5875 1175);
DISPLAY INVISIBLE (-5875 1175);
FORCEPROP 1 LAST PATH I11
J 0
(-5825 1250);
DISPLAY 0.872340 (-5825 1250);
PAINT AQUA (-5825 1250);
DISPLAY INVISIBLE (-5825 1250);
FORCEPROP 2 LAST CDS_LIB pure_quanta_power
J 0
(-5900 1250);
DISPLAY INVISIBLE (-5900 1250);
FORCEADD Q_XTAL_4P_13BI_24GND..1
(-5525 1575);
FORCEPROP 1 LAST LOCATION Y4
J 0
(-5658 1941);
DISPLAY 0.489362 (-5658 1941);
PAINT SKYBLUE (-5658 1941);
FORCEPROP 0 LAST $SEC 1
J 0
(-5650 2075);
DISPLAY 0.680851 (-5650 2075);
PAINT MONO (-5650 2075);
DISPLAY INVISIBLE (-5650 2075);
FORCEPROP 0 LAST CDS_SEC 1
J 0
(-5650 2075);
DISPLAY 1.021277 (-5650 2075);
DISPLAY INVISIBLE (-5650 2075);
FORCEPROP 0 LASTPIN (-5800 1450) $PN 2
J 2
(-5810 1460);
DISPLAY 0.489362 (-5810 1460);
PAINT MONO (-5810 1460);
FORCEPROP 0 LASTPIN (-5250 1450) $PN 4
J 0
(-5240 1460);
DISPLAY 0.489362 (-5240 1460);
PAINT MONO (-5240 1460);
FORCEPROP 0 LASTPIN (-5800 1650) $PN 1
J 2
(-5810 1660);
DISPLAY 0.489362 (-5810 1660);
PAINT MONO (-5810 1660);
FORCEPROP 0 LASTPIN (-5250 1650) $PN 3
J 0
(-5240 1660);
DISPLAY 0.489362 (-5240 1660);
PAINT MONO (-5240 1660);
FORCEPROP 1 LAST PART_NUMBER BG648000055
J 0
(-5658 1850);
DISPLAY 0.489362 (-5658 1850);
PAINT SKYBLUE (-5658 1850);
FORCEPROP 2 LAST VALUE 48MHZ
J 0
(-5650 1975);
DISPLAY 0.489362 (-5650 1975);
PAINT SKYBLUE (-5650 1975);
FORCEPROP 1 LAST MATERIAL MISC 
J 0
(-5658 1754);
DISPLAY 0.489362 (-5658 1754);
PAINT SKYBLUE (-5658 1754);
FORCEPROP 2 LAST PART_TYPE SMLF
J 0
(-5650 2025);
DISPLAY 1.021277 (-5650 2025);
FORCEPROP 1 LAST PATH I12
J 0
(-5400 1400);
DISPLAY 0.723404 (-5400 1400);
PAINT GREEN (-5400 1400);
DISPLAY INVISIBLE (-5400 1400);
FORCEPROP 1 LAST CDS_LMAN_SYM_OUTLINE -125,175,125,-175
J 0
(-5525 1575);
DISPLAY 0.468085 (-5525 1575);
PAINT GREEN (-5525 1575);
DISPLAY INVISIBLE (-5525 1575);
FORCEPROP 1 LAST PIN_NAMES_ROTATE True
J 0
(-5525 1575);
DISPLAY 0.489362 (-5525 1575);
PAINT GREEN (-5525 1575);
DISPLAY INVISIBLE (-5525 1575);
FORCEPROP 2 LAST CDS_LIB pure_quanta
J 0
(-5525 1575);
DISPLAY INVISIBLE (-5525 1575);
FORCEADD OFFPAGE..2
(-7625 2175);
FORCEPROP 2 LAST $XR1 81 
J 0
(-7346 2175);
DISPLAY 0.638298 (-7346 2175);
PAINT MONO (-7346 2175);
FORCEPROP 2 LAST $XR0 55 
J 0
(-7436 2175);
DISPLAY 0.638298 (-7436 2175);
PAINT MONO (-7436 2175);
FORCEPROP 2 LAST PATH I126
J 2
(-7425 2225);
DISPLAY 1.021277 (-7425 2225);
DISPLAY INVISIBLE (-7425 2225);
FORCEPROP 1 LAST COMMENT_BODY TRUE
J 0
(-7670 2080);
DISPLAY 0.872340 (-7670 2080);
PAINT GREEN (-7670 2080);
DISPLAY INVISIBLE (-7670 2080);
FORCEPROP 1 LAST OFFPAGE TRUE
J 0
(-7300 2050);
DISPLAY 0.872340 (-7300 2050);
PAINT GREEN (-7300 2050);
DISPLAY INVISIBLE (-7300 2050);
FORCEPROP 2 LAST CDS_LIB standard
J 2
(-7625 2175);
DISPLAY INVISIBLE (-7625 2175);
FORCEADD OFFPAGE..2
(-7625 2275);
FORCEPROP 2 LAST $XR1 81 
J 0
(-7346 2275);
DISPLAY 0.638298 (-7346 2275);
PAINT MONO (-7346 2275);
FORCEPROP 2 LAST $XR0 55 
J 0
(-7436 2275);
DISPLAY 0.638298 (-7436 2275);
PAINT MONO (-7436 2275);
FORCEPROP 2 LAST PATH I127
J 2
(-7375 2325);
DISPLAY 1.021277 (-7375 2325);
DISPLAY INVISIBLE (-7375 2325);
FORCEPROP 1 LAST COMMENT_BODY TRUE
J 0
(-7670 2180);
DISPLAY 0.872340 (-7670 2180);
PAINT GREEN (-7670 2180);
DISPLAY INVISIBLE (-7670 2180);
FORCEPROP 1 LAST OFFPAGE TRUE
J 0
(-7300 2150);
DISPLAY 0.872340 (-7300 2150);
PAINT GREEN (-7300 2150);
DISPLAY INVISIBLE (-7300 2150);
FORCEPROP 2 LAST CDS_LIB standard
J 2
(-7625 2275);
DISPLAY INVISIBLE (-7625 2275);
FORCEADD OFFPAGE..2
(-7625 2225);
FORCEPROP 2 LAST $XR1 81 
J 0
(-7346 2225);
DISPLAY 0.638298 (-7346 2225);
PAINT MONO (-7346 2225);
FORCEPROP 2 LAST $XR0 55 
J 0
(-7436 2225);
DISPLAY 0.638298 (-7436 2225);
PAINT MONO (-7436 2225);
FORCEPROP 2 LAST PATH I128
J 2
(-7375 2275);
DISPLAY 1.021277 (-7375 2275);
DISPLAY INVISIBLE (-7375 2275);
FORCEPROP 1 LAST COMMENT_BODY TRUE
J 0
(-7670 2130);
DISPLAY 0.872340 (-7670 2130);
PAINT GREEN (-7670 2130);
DISPLAY INVISIBLE (-7670 2130);
FORCEPROP 1 LAST OFFPAGE TRUE
J 0
(-7300 2100);
DISPLAY 0.872340 (-7300 2100);
PAINT GREEN (-7300 2100);
DISPLAY INVISIBLE (-7300 2100);
FORCEPROP 2 LAST CDS_LIB standard
J 2
(-7625 2225);
DISPLAY INVISIBLE (-7625 2225);
FORCEADD OFFPAGE..2
(-7625 2325);
FORCEPROP 2 LAST $XR1 81 
J 0
(-7346 2325);
DISPLAY 0.638298 (-7346 2325);
PAINT MONO (-7346 2325);
FORCEPROP 2 LAST $XR0 55 
J 0
(-7436 2325);
DISPLAY 0.638298 (-7436 2325);
PAINT MONO (-7436 2325);
FORCEPROP 2 LAST PATH I129
J 2
(-7375 2375);
DISPLAY 1.021277 (-7375 2375);
DISPLAY INVISIBLE (-7375 2375);
FORCEPROP 1 LAST COMMENT_BODY TRUE
J 0
(-7670 2230);
DISPLAY 0.872340 (-7670 2230);
PAINT GREEN (-7670 2230);
DISPLAY INVISIBLE (-7670 2230);
FORCEPROP 1 LAST OFFPAGE TRUE
J 0
(-7300 2200);
DISPLAY 0.872340 (-7300 2200);
PAINT GREEN (-7300 2200);
DISPLAY INVISIBLE (-7300 2200);
FORCEPROP 2 LAST CDS_LIB standard
J 0
(-7625 2325);
DISPLAY INVISIBLE (-7625 2325);
FORCEADD UNIVERSAL_GND..1
(-5125 1250);
FORCEPROP 3 LASTPIN (-5125 1300) SIG_NAME GND\g
J 0
(-5115 1310);
DISPLAY 0.659574 (-5115 1310);
PAINT MONO (-5115 1310);
DISPLAY INVISIBLE (-5115 1310);
FORCEPROP 1 LAST HDL_POWER GND
J 1
(-5100 1175);
DISPLAY 0.872340 (-5100 1175);
PAINT GREEN (-5100 1175);
DISPLAY INVISIBLE (-5100 1175);
FORCEPROP 1 LAST PATH I13
J 0
(-5050 1250);
DISPLAY 0.872340 (-5050 1250);
PAINT AQUA (-5050 1250);
DISPLAY INVISIBLE (-5050 1250);
FORCEPROP 2 LAST CDS_LIB pure_quanta_power
J 0
(-5125 1250);
DISPLAY INVISIBLE (-5125 1250);
FORCEADD Q_RES..1
R 2
(-8625 2225);
FORCEPROP 1 LAST LOCATION R546
J 0
(-8350 2225);
DISPLAY 0.489362 (-8350 2225);
PAINT SKYBLUE (-8350 2225);
FORCEPROP 0 LAST $SEC 1
J 2
(-8475 2275);
DISPLAY 0.680851 (-8475 2275);
PAINT MONO (-8475 2275);
DISPLAY INVISIBLE (-8475 2275);
FORCEPROP 0 LAST CDS_SEC 1
J 2
(-8475 2275);
DISPLAY 1.021277 (-8475 2275);
DISPLAY INVISIBLE (-8475 2275);
FORCEPROP 1 LASTPIN (-8525 2225) $PN 1
J 2
(-8537 2237);
DISPLAY 0.489362 (-8537 2237);
PAINT MONO (-8537 2237);
FORCEPROP 1 LASTPIN (-8725 2225) $PN 2
J 2
(-8687 2237);
DISPLAY 0.489362 (-8687 2237);
PAINT MONO (-8687 2237);
FORCEPROP 1 LAST VALUE 4.7K
J 0
(-8875 2225);
DISPLAY 0.489362 (-8875 2225);
PAINT SKYBLUE (-8875 2225);
FORCEPROP 1 LAST PACK_TYPE 0402LF
J 2
(-8875 2075);
DISPLAY 0.510638 (-8875 2075);
PAINT SKYBLUE (-8875 2075);
DISPLAY INVISIBLE (-8875 2075);
FORCEPROP 1 LAST PART_NUMBER TMP_QCS24702JB38
J 2
(-8575 2325);
DISPLAY 0.510638 (-8575 2325);
PAINT SKYBLUE (-8575 2325);
DISPLAY INVISIBLE (-8575 2325);
FORCEPROP 1 LAST TOLERANCE 5%
J 2
(-8750 2225);
DISPLAY 0.510638 (-8750 2225);
PAINT SKYBLUE (-8750 2225);
DISPLAY INVISIBLE (-8750 2225);
FORCEPROP 1 LAST MATERIAL CHIP
J 2
(-8725 2200);
DISPLAY 0.489362 (-8725 2200);
PAINT SKYBLUE (-8725 2200);
DISPLAY INVISIBLE (-8725 2200);
FORCEPROP 1 LAST WATTAGE 1/16W
J 0
(-8600 2075);
DISPLAY 0.510638 (-8600 2075);
PAINT SKYBLUE (-8600 2075);
DISPLAY INVISIBLE (-8600 2075);
FORCEPROP 1 LAST PATH I130
J 2
(-8575 2375);
DISPLAY 0.978723 (-8575 2375);
PAINT WHITE (-8575 2375);
DISPLAY INVISIBLE (-8575 2375);
FORCEPROP 2 LAST CDS_LIB pure_quanta
J 2
(-8625 2225);
DISPLAY INVISIBLE (-8625 2225);
FORCEADD Q_RES..1
R 2
(-8625 2275);
FORCEPROP 1 LAST LOCATION R545
J 0
(-8350 2275);
DISPLAY 0.489362 (-8350 2275);
PAINT SKYBLUE (-8350 2275);
FORCEPROP 0 LAST $SEC 1
J 2
(-8475 2325);
DISPLAY 0.680851 (-8475 2325);
PAINT MONO (-8475 2325);
DISPLAY INVISIBLE (-8475 2325);
FORCEPROP 0 LAST CDS_SEC 1
J 2
(-8475 2325);
DISPLAY 1.021277 (-8475 2325);
DISPLAY INVISIBLE (-8475 2325);
FORCEPROP 1 LASTPIN (-8525 2275) $PN 1
J 2
(-8537 2287);
DISPLAY 0.489362 (-8537 2287);
PAINT MONO (-8537 2287);
FORCEPROP 1 LASTPIN (-8725 2275) $PN 2
J 2
(-8687 2287);
DISPLAY 0.489362 (-8687 2287);
PAINT MONO (-8687 2287);
FORCEPROP 1 LAST VALUE 4.7K
J 0
(-8875 2275);
DISPLAY 0.489362 (-8875 2275);
PAINT SKYBLUE (-8875 2275);
FORCEPROP 1 LAST PACK_TYPE 0402LF
J 2
(-8875 2125);
DISPLAY 0.510638 (-8875 2125);
PAINT SKYBLUE (-8875 2125);
DISPLAY INVISIBLE (-8875 2125);
FORCEPROP 1 LAST PART_NUMBER TMP_QCS24702JB38
J 2
(-8575 2375);
DISPLAY 0.510638 (-8575 2375);
PAINT SKYBLUE (-8575 2375);
DISPLAY INVISIBLE (-8575 2375);
FORCEPROP 1 LAST TOLERANCE 5%
J 2
(-8750 2275);
DISPLAY 0.510638 (-8750 2275);
PAINT SKYBLUE (-8750 2275);
DISPLAY INVISIBLE (-8750 2275);
FORCEPROP 1 LAST MATERIAL CHIP
J 2
(-8725 2250);
DISPLAY 0.489362 (-8725 2250);
PAINT SKYBLUE (-8725 2250);
DISPLAY INVISIBLE (-8725 2250);
FORCEPROP 1 LAST WATTAGE 1/16W
J 0
(-8600 2125);
DISPLAY 0.510638 (-8600 2125);
PAINT SKYBLUE (-8600 2125);
DISPLAY INVISIBLE (-8600 2125);
FORCEPROP 1 LAST PATH I131
J 2
(-8575 2425);
DISPLAY 0.978723 (-8575 2425);
PAINT WHITE (-8575 2425);
DISPLAY INVISIBLE (-8575 2425);
FORCEPROP 2 LAST CDS_LIB pure_quanta
J 2
(-8625 2275);
DISPLAY INVISIBLE (-8625 2275);
FORCEADD Q_RES..1
R 2
(-8625 2325);
FORCEPROP 1 LAST LOCATION R544
J 0
(-8350 2325);
DISPLAY 0.489362 (-8350 2325);
PAINT SKYBLUE (-8350 2325);
FORCEPROP 0 LAST $SEC 1
J 2
(-8475 2375);
DISPLAY 0.680851 (-8475 2375);
PAINT MONO (-8475 2375);
DISPLAY INVISIBLE (-8475 2375);
FORCEPROP 0 LAST CDS_SEC 1
J 2
(-8475 2375);
DISPLAY 1.021277 (-8475 2375);
DISPLAY INVISIBLE (-8475 2375);
FORCEPROP 1 LASTPIN (-8525 2325) $PN 1
J 2
(-8537 2337);
DISPLAY 0.489362 (-8537 2337);
PAINT MONO (-8537 2337);
FORCEPROP 1 LASTPIN (-8725 2325) $PN 2
J 2
(-8687 2337);
DISPLAY 0.489362 (-8687 2337);
PAINT MONO (-8687 2337);
FORCEPROP 1 LAST VALUE 4.7K
J 0
(-8875 2325);
DISPLAY 0.489362 (-8875 2325);
PAINT SKYBLUE (-8875 2325);
FORCEPROP 1 LAST PACK_TYPE 0402LF
J 2
(-8875 2175);
DISPLAY 0.510638 (-8875 2175);
PAINT SKYBLUE (-8875 2175);
DISPLAY INVISIBLE (-8875 2175);
FORCEPROP 1 LAST PART_NUMBER TMP_QCS24702JB38
J 2
(-8575 2425);
DISPLAY 0.510638 (-8575 2425);
PAINT SKYBLUE (-8575 2425);
DISPLAY INVISIBLE (-8575 2425);
FORCEPROP 1 LAST TOLERANCE 5%
J 2
(-8750 2325);
DISPLAY 0.510638 (-8750 2325);
PAINT SKYBLUE (-8750 2325);
DISPLAY INVISIBLE (-8750 2325);
FORCEPROP 1 LAST MATERIAL CHIP
J 2
(-8725 2300);
DISPLAY 0.489362 (-8725 2300);
PAINT SKYBLUE (-8725 2300);
DISPLAY INVISIBLE (-8725 2300);
FORCEPROP 1 LAST WATTAGE 1/16W
J 0
(-8600 2175);
DISPLAY 0.510638 (-8600 2175);
PAINT SKYBLUE (-8600 2175);
DISPLAY INVISIBLE (-8600 2175);
FORCEPROP 1 LAST PATH I132
J 2
(-8575 2475);
DISPLAY 0.978723 (-8575 2475);
PAINT WHITE (-8575 2475);
DISPLAY INVISIBLE (-8575 2475);
FORCEPROP 2 LAST CDS_LIB pure_quanta
J 2
(-8625 2325);
DISPLAY INVISIBLE (-8625 2325);
FORCEADD UNIVERSAL_POWER..1
R 2
(-8975 2425);
FORCEPROP 3 LASTPIN (-8975 2375) SIG_NAME PVDD18_S5_P1\g
J 0
(-8965 2385);
DISPLAY 0.659574 (-8965 2385);
PAINT MONO (-8965 2385);
DISPLAY INVISIBLE (-8965 2385);
FORCEPROP 1 LAST HDL_POWER PVDD18_S5_P1
J 1
(-8950 2475);
DISPLAY 0.489362 (-8950 2475);
PAINT GREEN (-8950 2475);
FORCEPROP 1 LAST PATH I133
J 2
(-9025 2450);
DISPLAY 0.872340 (-9025 2450);
PAINT AQUA (-9025 2450);
DISPLAY INVISIBLE (-9025 2450);
FORCEPROP 2 LAST CDS_LIB pure_quanta_power
J 2
(-8975 2425);
DISPLAY INVISIBLE (-8975 2425);
FORCEADD Q_RES..1
R 2
(-8625 2175);
FORCEPROP 1 LAST LOCATION R547
J 0
(-8350 2175);
DISPLAY 0.489362 (-8350 2175);
PAINT SKYBLUE (-8350 2175);
FORCEPROP 0 LAST $SEC 1
J 2
(-8475 2225);
DISPLAY 0.680851 (-8475 2225);
PAINT MONO (-8475 2225);
DISPLAY INVISIBLE (-8475 2225);
FORCEPROP 0 LAST CDS_SEC 1
J 2
(-8475 2225);
DISPLAY 1.021277 (-8475 2225);
DISPLAY INVISIBLE (-8475 2225);
FORCEPROP 1 LASTPIN (-8525 2175) $PN 1
J 2
(-8537 2187);
DISPLAY 0.489362 (-8537 2187);
PAINT MONO (-8537 2187);
FORCEPROP 1 LASTPIN (-8725 2175) $PN 2
J 2
(-8687 2187);
DISPLAY 0.489362 (-8687 2187);
PAINT MONO (-8687 2187);
FORCEPROP 1 LAST VALUE 4.7K
J 0
(-8875 2175);
DISPLAY 0.489362 (-8875 2175);
PAINT SKYBLUE (-8875 2175);
FORCEPROP 1 LAST PACK_TYPE 0402LF
J 2
(-8875 2025);
DISPLAY 0.510638 (-8875 2025);
PAINT SKYBLUE (-8875 2025);
DISPLAY INVISIBLE (-8875 2025);
FORCEPROP 1 LAST PART_NUMBER TMP_QCS24702JB38
J 2
(-8575 2275);
DISPLAY 0.510638 (-8575 2275);
PAINT SKYBLUE (-8575 2275);
DISPLAY INVISIBLE (-8575 2275);
FORCEPROP 1 LAST TOLERANCE 5%
J 2
(-8750 2175);
DISPLAY 0.510638 (-8750 2175);
PAINT SKYBLUE (-8750 2175);
DISPLAY INVISIBLE (-8750 2175);
FORCEPROP 1 LAST MATERIAL CHIP
J 2
(-8725 2150);
DISPLAY 0.489362 (-8725 2150);
PAINT SKYBLUE (-8725 2150);
DISPLAY INVISIBLE (-8725 2150);
FORCEPROP 1 LAST WATTAGE 1/16W
J 0
(-8600 2025);
DISPLAY 0.510638 (-8600 2025);
PAINT SKYBLUE (-8600 2025);
DISPLAY INVISIBLE (-8600 2025);
FORCEPROP 1 LAST PATH I134
J 2
(-8575 2325);
DISPLAY 0.978723 (-8575 2325);
PAINT WHITE (-8575 2325);
DISPLAY INVISIBLE (-8575 2325);
FORCEPROP 2 LAST CDS_LIB pure_quanta
J 2
(-8625 2175);
DISPLAY INVISIBLE (-8625 2175);
FORCEADD Q_RES..1
R 2
(-8625 1625);
FORCEPROP 1 LAST LOCATION R548
J 0
(-8350 1625);
DISPLAY 0.489362 (-8350 1625);
PAINT SKYBLUE (-8350 1625);
FORCEPROP 0 LAST $SEC 1
J 2
(-8475 1675);
DISPLAY 0.680851 (-8475 1675);
PAINT MONO (-8475 1675);
DISPLAY INVISIBLE (-8475 1675);
FORCEPROP 0 LAST CDS_SEC 1
J 2
(-8475 1675);
DISPLAY 1.021277 (-8475 1675);
DISPLAY INVISIBLE (-8475 1675);
FORCEPROP 1 LASTPIN (-8525 1625) $PN 1
J 2
(-8537 1637);
DISPLAY 0.489362 (-8537 1637);
PAINT MONO (-8537 1637);
FORCEPROP 1 LASTPIN (-8725 1625) $PN 2
J 2
(-8687 1637);
DISPLAY 0.489362 (-8687 1637);
PAINT MONO (-8687 1637);
FORCEPROP 1 LAST MATERIAL EMPTY
J 2
(-8375 1625);
DISPLAY 0.489362 (-8375 1625);
PAINT RED (-8375 1625);
FORCEPROP 1 LAST VALUE 4.7K
J 0
(-8875 1625);
DISPLAY 0.489362 (-8875 1625);
PAINT SKYBLUE (-8875 1625);
FORCEPROP 1 LAST PACK_TYPE 0402LF
J 2
(-8875 1475);
DISPLAY 0.510638 (-8875 1475);
PAINT SKYBLUE (-8875 1475);
DISPLAY INVISIBLE (-8875 1475);
FORCEPROP 1 LAST PART_NUMBER TMP_QCS24702JB38
J 2
(-8575 1725);
DISPLAY 0.510638 (-8575 1725);
PAINT SKYBLUE (-8575 1725);
DISPLAY INVISIBLE (-8575 1725);
FORCEPROP 1 LAST TOLERANCE 5%
J 2
(-8750 1625);
DISPLAY 0.510638 (-8750 1625);
PAINT SKYBLUE (-8750 1625);
DISPLAY INVISIBLE (-8750 1625);
FORCEPROP 1 LAST WATTAGE 1/16W
J 0
(-8600 1475);
DISPLAY 0.510638 (-8600 1475);
PAINT SKYBLUE (-8600 1475);
DISPLAY INVISIBLE (-8600 1475);
FORCEPROP 1 LAST PATH I139
J 2
(-8575 1775);
DISPLAY 0.978723 (-8575 1775);
PAINT WHITE (-8575 1775);
DISPLAY INVISIBLE (-8575 1775);
FORCEPROP 2 LAST CDS_LIB pure_quanta
J 2
(-8625 1625);
DISPLAY INVISIBLE (-8625 1625);
FORCEADD UNIVERSAL_GND..1
(-4900 525);
FORCEPROP 3 LASTPIN (-4900 575) SIG_NAME GND\g
J 0
(-4890 585);
DISPLAY 0.659574 (-4890 585);
PAINT MONO (-4890 585);
DISPLAY INVISIBLE (-4890 585);
FORCEPROP 1 LAST HDL_POWER GND
J 1
(-4875 450);
DISPLAY 0.872340 (-4875 450);
PAINT GREEN (-4875 450);
DISPLAY INVISIBLE (-4875 450);
FORCEPROP 1 LAST PATH I14
J 0
(-4825 525);
DISPLAY 0.872340 (-4825 525);
PAINT AQUA (-4825 525);
DISPLAY INVISIBLE (-4825 525);
FORCEPROP 2 LAST CDS_LIB pure_quanta_power
J 0
(-4900 525);
DISPLAY INVISIBLE (-4900 525);
FORCEADD OFFPAGE..2
(-7625 1625);
FORCEPROP 2 LAST $XR0 55 
J 0
(-7436 1625);
DISPLAY 0.638298 (-7436 1625);
PAINT MONO (-7436 1625);
FORCEPROP 2 LAST PATH I140
J 0
(-7450 1700);
DISPLAY 1.021277 (-7450 1700);
DISPLAY INVISIBLE (-7450 1700);
FORCEPROP 1 LAST COMMENT_BODY TRUE
J 0
(-7670 1530);
DISPLAY 0.872340 (-7670 1530);
PAINT GREEN (-7670 1530);
DISPLAY INVISIBLE (-7670 1530);
FORCEPROP 1 LAST OFFPAGE TRUE
J 0
(-7300 1500);
DISPLAY 0.872340 (-7300 1500);
PAINT GREEN (-7300 1500);
DISPLAY INVISIBLE (-7300 1500);
FORCEPROP 2 LAST CDS_LIB standard
J 2
(-7625 1625);
DISPLAY INVISIBLE (-7625 1625);
FORCEADD OFFPAGE..2
(-7625 1575);
FORCEPROP 2 LAST $XR0 55 
J 0
(-7436 1575);
DISPLAY 0.638298 (-7436 1575);
PAINT MONO (-7436 1575);
FORCEPROP 2 LAST PATH I141
J 0
(-7450 1650);
DISPLAY 1.021277 (-7450 1650);
DISPLAY INVISIBLE (-7450 1650);
FORCEPROP 1 LAST COMMENT_BODY TRUE
J 0
(-7670 1480);
DISPLAY 0.872340 (-7670 1480);
PAINT GREEN (-7670 1480);
DISPLAY INVISIBLE (-7670 1480);
FORCEPROP 1 LAST OFFPAGE TRUE
J 0
(-7300 1450);
DISPLAY 0.872340 (-7300 1450);
PAINT GREEN (-7300 1450);
DISPLAY INVISIBLE (-7300 1450);
FORCEPROP 2 LAST CDS_LIB standard
J 2
(-7625 1575);
DISPLAY INVISIBLE (-7625 1575);
FORCEADD Q_RES..1
R 2
(-8625 1575);
FORCEPROP 1 LAST LOCATION R549
J 0
(-8350 1575);
DISPLAY 0.489362 (-8350 1575);
PAINT SKYBLUE (-8350 1575);
FORCEPROP 0 LAST $SEC 1
J 2
(-8475 1625);
DISPLAY 0.680851 (-8475 1625);
PAINT MONO (-8475 1625);
DISPLAY INVISIBLE (-8475 1625);
FORCEPROP 0 LAST CDS_SEC 1
J 2
(-8475 1625);
DISPLAY 1.021277 (-8475 1625);
DISPLAY INVISIBLE (-8475 1625);
FORCEPROP 1 LASTPIN (-8525 1575) $PN 1
J 2
(-8537 1587);
DISPLAY 0.489362 (-8537 1587);
PAINT MONO (-8537 1587);
FORCEPROP 1 LASTPIN (-8725 1575) $PN 2
J 2
(-8687 1587);
DISPLAY 0.489362 (-8687 1587);
PAINT MONO (-8687 1587);
FORCEPROP 1 LAST MATERIAL EMPTY
J 2
(-8375 1575);
DISPLAY 0.489362 (-8375 1575);
PAINT RED (-8375 1575);
FORCEPROP 1 LAST VALUE 4.7K
J 0
(-8875 1575);
DISPLAY 0.489362 (-8875 1575);
PAINT SKYBLUE (-8875 1575);
FORCEPROP 1 LAST PACK_TYPE 0402LF
J 2
(-8875 1425);
DISPLAY 0.510638 (-8875 1425);
PAINT SKYBLUE (-8875 1425);
DISPLAY INVISIBLE (-8875 1425);
FORCEPROP 1 LAST PART_NUMBER TMP_QCS24702JB38
J 2
(-8575 1675);
DISPLAY 0.510638 (-8575 1675);
PAINT SKYBLUE (-8575 1675);
DISPLAY INVISIBLE (-8575 1675);
FORCEPROP 1 LAST TOLERANCE 5%
J 2
(-8750 1575);
DISPLAY 0.510638 (-8750 1575);
PAINT SKYBLUE (-8750 1575);
DISPLAY INVISIBLE (-8750 1575);
FORCEPROP 1 LAST WATTAGE 1/16W
J 0
(-8600 1425);
DISPLAY 0.510638 (-8600 1425);
PAINT SKYBLUE (-8600 1425);
DISPLAY INVISIBLE (-8600 1425);
FORCEPROP 1 LAST PATH I142
J 2
(-8575 1725);
DISPLAY 0.978723 (-8575 1725);
PAINT WHITE (-8575 1725);
DISPLAY INVISIBLE (-8575 1725);
FORCEPROP 2 LAST CDS_LIB pure_quanta
J 2
(-8625 1575);
DISPLAY INVISIBLE (-8625 1575);
FORCEADD Q_RES..1
R 2
(-8625 2075);
FORCEPROP 1 LAST LOCATION R550
J 0
(-8350 2075);
DISPLAY 0.489362 (-8350 2075);
PAINT SKYBLUE (-8350 2075);
FORCEPROP 0 LAST $SEC 1
J 2
(-8475 2125);
DISPLAY 0.680851 (-8475 2125);
PAINT MONO (-8475 2125);
DISPLAY INVISIBLE (-8475 2125);
FORCEPROP 0 LAST CDS_SEC 1
J 2
(-8475 2125);
DISPLAY 1.021277 (-8475 2125);
DISPLAY INVISIBLE (-8475 2125);
FORCEPROP 1 LASTPIN (-8525 2075) $PN 1
J 2
(-8537 2087);
DISPLAY 0.489362 (-8537 2087);
PAINT MONO (-8537 2087);
FORCEPROP 1 LASTPIN (-8725 2075) $PN 2
J 2
(-8687 2087);
DISPLAY 0.489362 (-8687 2087);
PAINT MONO (-8687 2087);
FORCEPROP 1 LAST VALUE 4.7K
J 0
(-8875 2075);
DISPLAY 0.489362 (-8875 2075);
PAINT SKYBLUE (-8875 2075);
FORCEPROP 1 LAST PACK_TYPE 0402LF
J 2
(-8875 1925);
DISPLAY 0.510638 (-8875 1925);
PAINT SKYBLUE (-8875 1925);
DISPLAY INVISIBLE (-8875 1925);
FORCEPROP 1 LAST PART_NUMBER TMP_QCS24702JB38
J 2
(-8575 2175);
DISPLAY 0.510638 (-8575 2175);
PAINT SKYBLUE (-8575 2175);
DISPLAY INVISIBLE (-8575 2175);
FORCEPROP 1 LAST TOLERANCE 5%
J 2
(-8750 2075);
DISPLAY 0.510638 (-8750 2075);
PAINT SKYBLUE (-8750 2075);
DISPLAY INVISIBLE (-8750 2075);
FORCEPROP 1 LAST MATERIAL CHIP
J 2
(-8725 2050);
DISPLAY 0.489362 (-8725 2050);
PAINT SKYBLUE (-8725 2050);
DISPLAY INVISIBLE (-8725 2050);
FORCEPROP 1 LAST WATTAGE 1/16W
J 0
(-8600 1925);
DISPLAY 0.510638 (-8600 1925);
PAINT SKYBLUE (-8600 1925);
DISPLAY INVISIBLE (-8600 1925);
FORCEPROP 1 LAST PATH I143
J 2
(-8575 2225);
DISPLAY 0.978723 (-8575 2225);
PAINT WHITE (-8575 2225);
DISPLAY INVISIBLE (-8575 2225);
FORCEPROP 2 LAST CDS_LIB pure_quanta
J 2
(-8625 2075);
DISPLAY INVISIBLE (-8625 2075);
FORCEADD OFFPAGE..2
(-7625 2075);
FORCEPROP 2 LAST $XR1 80 
J 0
(-7346 2075);
DISPLAY 0.638298 (-7346 2075);
PAINT MONO (-7346 2075);
FORCEPROP 2 LAST $XR0 55 
J 0
(-7436 2075);
DISPLAY 0.638298 (-7436 2075);
PAINT MONO (-7436 2075);
FORCEPROP 2 LAST PATH I144
J 0
(-7450 2150);
DISPLAY 1.021277 (-7450 2150);
DISPLAY INVISIBLE (-7450 2150);
FORCEPROP 1 LAST COMMENT_BODY TRUE
J 0
(-7670 1980);
DISPLAY 0.872340 (-7670 1980);
PAINT GREEN (-7670 1980);
DISPLAY INVISIBLE (-7670 1980);
FORCEPROP 1 LAST OFFPAGE TRUE
J 0
(-7300 1950);
DISPLAY 0.872340 (-7300 1950);
PAINT GREEN (-7300 1950);
DISPLAY INVISIBLE (-7300 1950);
FORCEPROP 2 LAST CDS_LIB standard
J 2
(-7625 2075);
DISPLAY INVISIBLE (-7625 2075);
FORCEADD Q_RES..1
R 2
(-8625 2025);
FORCEPROP 1 LAST LOCATION R551
J 0
(-8350 2025);
DISPLAY 0.489362 (-8350 2025);
PAINT SKYBLUE (-8350 2025);
FORCEPROP 0 LAST $SEC 1
J 2
(-8475 2075);
DISPLAY 0.680851 (-8475 2075);
PAINT MONO (-8475 2075);
DISPLAY INVISIBLE (-8475 2075);
FORCEPROP 0 LAST CDS_SEC 1
J 2
(-8475 2075);
DISPLAY 1.021277 (-8475 2075);
DISPLAY INVISIBLE (-8475 2075);
FORCEPROP 1 LASTPIN (-8525 2025) $PN 1
J 2
(-8537 2037);
DISPLAY 0.489362 (-8537 2037);
PAINT MONO (-8537 2037);
FORCEPROP 1 LASTPIN (-8725 2025) $PN 2
J 2
(-8687 2037);
DISPLAY 0.489362 (-8687 2037);
PAINT MONO (-8687 2037);
FORCEPROP 1 LAST VALUE 4.7K
J 0
(-8875 2025);
DISPLAY 0.489362 (-8875 2025);
PAINT SKYBLUE (-8875 2025);
FORCEPROP 1 LAST PACK_TYPE 0402LF
J 2
(-8875 1875);
DISPLAY 0.510638 (-8875 1875);
PAINT SKYBLUE (-8875 1875);
DISPLAY INVISIBLE (-8875 1875);
FORCEPROP 1 LAST PART_NUMBER TMP_QCS24702JB38
J 2
(-8575 2125);
DISPLAY 0.510638 (-8575 2125);
PAINT SKYBLUE (-8575 2125);
DISPLAY INVISIBLE (-8575 2125);
FORCEPROP 1 LAST TOLERANCE 5%
J 2
(-8750 2025);
DISPLAY 0.510638 (-8750 2025);
PAINT SKYBLUE (-8750 2025);
DISPLAY INVISIBLE (-8750 2025);
FORCEPROP 1 LAST MATERIAL CHIP
J 2
(-8725 2000);
DISPLAY 0.489362 (-8725 2000);
PAINT SKYBLUE (-8725 2000);
DISPLAY INVISIBLE (-8725 2000);
FORCEPROP 1 LAST WATTAGE 1/16W
J 0
(-8600 1875);
DISPLAY 0.510638 (-8600 1875);
PAINT SKYBLUE (-8600 1875);
DISPLAY INVISIBLE (-8600 1875);
FORCEPROP 1 LAST PATH I148
J 2
(-8575 2175);
DISPLAY 0.978723 (-8575 2175);
PAINT WHITE (-8575 2175);
DISPLAY INVISIBLE (-8575 2175);
FORCEPROP 2 LAST CDS_LIB pure_quanta
J 2
(-8625 2025);
DISPLAY INVISIBLE (-8625 2025);
FORCEADD OFFPAGE..2
(-7625 2025);
FORCEPROP 2 LAST $XR1 80 
J 0
(-7346 2025);
DISPLAY 0.638298 (-7346 2025);
PAINT MONO (-7346 2025);
FORCEPROP 2 LAST $XR0 55 
J 0
(-7436 2025);
DISPLAY 0.638298 (-7436 2025);
PAINT MONO (-7436 2025);
FORCEPROP 2 LAST PATH I149
J 0
(-7450 2100);
DISPLAY 1.021277 (-7450 2100);
DISPLAY INVISIBLE (-7450 2100);
FORCEPROP 1 LAST COMMENT_BODY TRUE
J 0
(-7670 1930);
DISPLAY 0.872340 (-7670 1930);
PAINT GREEN (-7670 1930);
DISPLAY INVISIBLE (-7670 1930);
FORCEPROP 1 LAST OFFPAGE TRUE
J 0
(-7300 1900);
DISPLAY 0.872340 (-7300 1900);
PAINT GREEN (-7300 1900);
DISPLAY INVISIBLE (-7300 1900);
FORCEPROP 2 LAST CDS_LIB standard
J 2
(-7625 2025);
DISPLAY INVISIBLE (-7625 2025);
FORCEADD Q_CAP..1
(-4900 825);
FORCEPROP 1 LAST LOCATION C237
J 0
(-4850 925);
DISPLAY 0.489362 (-4850 925);
PAINT SKYBLUE (-4850 925);
FORCEPROP 0 LAST $SEC 1
J 0
(-4850 975);
DISPLAY 0.680851 (-4850 975);
PAINT MONO (-4850 975);
DISPLAY INVISIBLE (-4850 975);
FORCEPROP 0 LAST CDS_SEC 1
J 0
(-4850 975);
DISPLAY 1.021277 (-4850 975);
DISPLAY INVISIBLE (-4850 975);
FORCEPROP 1 LASTPIN (-4900 925) $PN 1
J 0
(-4890 905);
DISPLAY 0.489362 (-4890 905);
PAINT MONO (-4890 905);
FORCEPROP 1 LASTPIN (-4900 725) $PN 2
J 0
(-4890 705);
DISPLAY 0.489362 (-4890 705);
PAINT MONO (-4890 705);
FORCEPROP 1 LAST VALUE 3.9P
J 0
(-4850 875);
DISPLAY 0.489362 (-4850 875);
PAINT SKYBLUE (-4850 875);
FORCEPROP 1 LAST TOLERANCE 0.1P
J 0
(-4850 775);
DISPLAY 0.489362 (-4850 775);
PAINT SKYBLUE (-4850 775);
FORCEPROP 1 LAST MATERIAL NPO
J 0
(-4850 725);
DISPLAY 0.489362 (-4850 725);
PAINT SKYBLUE (-4850 725);
FORCEPROP 1 LAST PART_NUMBER CH-3916TB01
J 0
(-4850 675);
DISPLAY 0.489362 (-4850 675);
PAINT SKYBLUE (-4850 675);
FORCEPROP 1 LAST PACK_TYPE C0402
J 0
(-4850 625);
DISPLAY 0.489362 (-4850 625);
PAINT SKYBLUE (-4850 625);
FORCEPROP 1 LAST VOLTAGE 50V
J 0
(-4850 825);
DISPLAY 0.489362 (-4850 825);
PAINT SKYBLUE (-4850 825);
FORCEPROP 1 LAST PATH I15
J 0
(-4850 975);
DISPLAY 0.978723 (-4850 975);
PAINT WHITE (-4850 975);
DISPLAY INVISIBLE (-4850 975);
FORCEPROP 2 LAST CDS_LIB pure_quanta
J 0
(-4900 825);
DISPLAY INVISIBLE (-4900 825);
FORCEADD OFFPAGE..2
(-7625 1975);
FORCEPROP 2 LAST $XR1 80 
J 0
(-7346 1975);
DISPLAY 0.638298 (-7346 1975);
PAINT MONO (-7346 1975);
FORCEPROP 2 LAST $XR0 55 
J 0
(-7436 1975);
DISPLAY 0.638298 (-7436 1975);
PAINT MONO (-7436 1975);
FORCEPROP 2 LAST PATH I154
J 0
(-7450 2050);
DISPLAY 1.021277 (-7450 2050);
DISPLAY INVISIBLE (-7450 2050);
FORCEPROP 1 LAST COMMENT_BODY TRUE
J 0
(-7670 1880);
DISPLAY 0.872340 (-7670 1880);
PAINT GREEN (-7670 1880);
DISPLAY INVISIBLE (-7670 1880);
FORCEPROP 1 LAST OFFPAGE TRUE
J 0
(-7300 1850);
DISPLAY 0.872340 (-7300 1850);
PAINT GREEN (-7300 1850);
DISPLAY INVISIBLE (-7300 1850);
FORCEPROP 2 LAST CDS_LIB standard
J 0
(-7625 1975);
DISPLAY INVISIBLE (-7625 1975);
FORCEADD Q_RES..1
R 2
(-8625 1975);
FORCEPROP 1 LAST LOCATION R553
J 0
(-8350 1975);
DISPLAY 0.489362 (-8350 1975);
PAINT SKYBLUE (-8350 1975);
FORCEPROP 0 LAST $SEC 1
J 2
(-8475 2025);
DISPLAY 0.680851 (-8475 2025);
PAINT MONO (-8475 2025);
DISPLAY INVISIBLE (-8475 2025);
FORCEPROP 0 LAST CDS_SEC 1
J 2
(-8475 2025);
DISPLAY 1.021277 (-8475 2025);
DISPLAY INVISIBLE (-8475 2025);
FORCEPROP 1 LASTPIN (-8525 1975) $PN 1
J 2
(-8537 1987);
DISPLAY 0.489362 (-8537 1987);
PAINT MONO (-8537 1987);
FORCEPROP 1 LASTPIN (-8725 1975) $PN 2
J 2
(-8687 1987);
DISPLAY 0.489362 (-8687 1987);
PAINT MONO (-8687 1987);
FORCEPROP 1 LAST VALUE 4.7K
J 0
(-8875 1975);
DISPLAY 0.489362 (-8875 1975);
PAINT SKYBLUE (-8875 1975);
FORCEPROP 1 LAST PART_NUMBER TMP_QCS24702JB38
J 2
(-8575 2075);
DISPLAY 0.404255 (-8575 2075);
PAINT SKYBLUE (-8575 2075);
DISPLAY INVISIBLE (-8575 2075);
FORCEPROP 1 LAST PACK_TYPE 0402LF
J 2
(-8875 1825);
DISPLAY 0.510638 (-8875 1825);
PAINT SKYBLUE (-8875 1825);
DISPLAY INVISIBLE (-8875 1825);
FORCEPROP 1 LAST TOLERANCE 5%
J 2
(-8750 1975);
DISPLAY 0.510638 (-8750 1975);
PAINT SKYBLUE (-8750 1975);
DISPLAY INVISIBLE (-8750 1975);
FORCEPROP 1 LAST MATERIAL CHIP
J 2
(-8725 1950);
DISPLAY 0.489362 (-8725 1950);
PAINT SKYBLUE (-8725 1950);
DISPLAY INVISIBLE (-8725 1950);
FORCEPROP 1 LAST WATTAGE 1/16W
J 0
(-8600 1825);
DISPLAY 0.510638 (-8600 1825);
PAINT SKYBLUE (-8600 1825);
DISPLAY INVISIBLE (-8600 1825);
FORCEPROP 1 LAST PATH I155
J 2
(-8575 2125);
DISPLAY 0.978723 (-8575 2125);
PAINT WHITE (-8575 2125);
DISPLAY INVISIBLE (-8575 2125);
FORCEPROP 2 LAST CDS_LIB pure_quanta
J 2
(-8625 1975);
DISPLAY INVISIBLE (-8625 1975);
FORCEADD OFFPAGE..2
(-1150 2125);
FORCEPROP 2 LAST $XR0 55 
J 0
(-961 2125);
DISPLAY 0.638298 (-961 2125);
PAINT MONO (-961 2125);
FORCEPROP 2 LAST PATH I16
J 0
(-975 2200);
DISPLAY 1.021277 (-975 2200);
DISPLAY INVISIBLE (-975 2200);
FORCEPROP 1 LAST COMMENT_BODY TRUE
J 0
(-1195 2030);
DISPLAY 0.872340 (-1195 2030);
PAINT GREEN (-1195 2030);
DISPLAY INVISIBLE (-1195 2030);
FORCEPROP 1 LAST OFFPAGE TRUE
J 0
(-825 2000);
DISPLAY 0.872340 (-825 2000);
PAINT GREEN (-825 2000);
DISPLAY INVISIBLE (-825 2000);
FORCEPROP 2 LAST CDS_LIB standard
J 0
(-1150 2125);
DISPLAY INVISIBLE (-1150 2125);
FORCEADD OFFPAGE..2
(-7625 1925);
FORCEPROP 2 LAST $XR2 84 
J 0
(-7256 1925);
DISPLAY 0.638298 (-7256 1925);
PAINT MONO (-7256 1925);
FORCEPROP 2 LAST $XR1 80 
J 0
(-7346 1925);
DISPLAY 0.638298 (-7346 1925);
PAINT MONO (-7346 1925);
FORCEPROP 2 LAST $XR0 55 
J 0
(-7436 1925);
DISPLAY 0.638298 (-7436 1925);
PAINT MONO (-7436 1925);
FORCEPROP 2 LAST PATH I163
J 0
(-7450 2000);
DISPLAY 1.021277 (-7450 2000);
DISPLAY INVISIBLE (-7450 2000);
FORCEPROP 1 LAST COMMENT_BODY TRUE
J 0
(-7670 1830);
DISPLAY 0.872340 (-7670 1830);
PAINT GREEN (-7670 1830);
DISPLAY INVISIBLE (-7670 1830);
FORCEPROP 1 LAST OFFPAGE TRUE
J 0
(-7300 1800);
DISPLAY 0.872340 (-7300 1800);
PAINT GREEN (-7300 1800);
DISPLAY INVISIBLE (-7300 1800);
FORCEPROP 2 LAST CDS_LIB standard
J 0
(-7625 1925);
DISPLAY INVISIBLE (-7625 1925);
FORCEADD OFFPAGE..2
(-7625 2125);
FORCEPROP 2 LAST $XR3 77 
J 0
(-7166 2125);
DISPLAY 0.638298 (-7166 2125);
PAINT MONO (-7166 2125);
FORCEPROP 2 LAST $XR2 84 
J 0
(-7256 2125);
DISPLAY 0.638298 (-7256 2125);
PAINT MONO (-7256 2125);
FORCEPROP 2 LAST $XR1 80 
J 0
(-7346 2125);
DISPLAY 0.638298 (-7346 2125);
PAINT MONO (-7346 2125);
FORCEPROP 2 LAST $XR0 55 
J 0
(-7436 2125);
DISPLAY 0.638298 (-7436 2125);
PAINT MONO (-7436 2125);
FORCEPROP 2 LAST PATH I165
J 0
(-7450 2200);
DISPLAY 1.021277 (-7450 2200);
DISPLAY INVISIBLE (-7450 2200);
FORCEPROP 1 LAST COMMENT_BODY TRUE
J 0
(-7670 2030);
DISPLAY 0.872340 (-7670 2030);
PAINT GREEN (-7670 2030);
DISPLAY INVISIBLE (-7670 2030);
FORCEPROP 1 LAST OFFPAGE TRUE
J 0
(-7300 2000);
DISPLAY 0.872340 (-7300 2000);
PAINT GREEN (-7300 2000);
DISPLAY INVISIBLE (-7300 2000);
FORCEPROP 2 LAST CDS_LIB standard
J 0
(-7625 2125);
DISPLAY INVISIBLE (-7625 2125);
FORCEADD OFFPAGE..2
(-7625 1875);
FORCEPROP 2 LAST $XR1 55 
J 0
(-7346 1875);
DISPLAY 0.638298 (-7346 1875);
PAINT MONO (-7346 1875);
FORCEPROP 2 LAST $XR0 80 
J 0
(-7436 1875);
DISPLAY 0.638298 (-7436 1875);
PAINT MONO (-7436 1875);
FORCEPROP 2 LAST PATH I168
J 0
(-7450 1950);
DISPLAY 1.021277 (-7450 1950);
DISPLAY INVISIBLE (-7450 1950);
FORCEPROP 1 LAST COMMENT_BODY TRUE
J 0
(-7670 1780);
DISPLAY 0.872340 (-7670 1780);
PAINT GREEN (-7670 1780);
DISPLAY INVISIBLE (-7670 1780);
FORCEPROP 1 LAST OFFPAGE TRUE
J 0
(-7300 1750);
DISPLAY 0.872340 (-7300 1750);
PAINT GREEN (-7300 1750);
DISPLAY INVISIBLE (-7300 1750);
FORCEPROP 2 LAST CDS_LIB standard
J 0
(-7625 1875);
DISPLAY INVISIBLE (-7625 1875);
FORCEADD Q_RES..1
R 2
(-8625 1875);
FORCEPROP 1 LAST LOCATION R558
J 0
(-8350 1875);
DISPLAY 0.489362 (-8350 1875);
PAINT SKYBLUE (-8350 1875);
FORCEPROP 0 LAST $SEC 1
J 2
(-8475 1925);
DISPLAY 0.680851 (-8475 1925);
PAINT MONO (-8475 1925);
DISPLAY INVISIBLE (-8475 1925);
FORCEPROP 0 LAST CDS_SEC 1
J 2
(-8475 1925);
DISPLAY 1.021277 (-8475 1925);
DISPLAY INVISIBLE (-8475 1925);
FORCEPROP 1 LASTPIN (-8525 1875) $PN 1
J 2
(-8537 1887);
DISPLAY 0.489362 (-8537 1887);
PAINT MONO (-8537 1887);
FORCEPROP 1 LASTPIN (-8725 1875) $PN 2
J 2
(-8687 1887);
DISPLAY 0.489362 (-8687 1887);
PAINT MONO (-8687 1887);
FORCEPROP 1 LAST VALUE 4.7K
J 0
(-8875 1875);
DISPLAY 0.489362 (-8875 1875);
PAINT SKYBLUE (-8875 1875);
FORCEPROP 1 LAST PACK_TYPE 0402LF
J 2
(-8875 1725);
DISPLAY 0.510638 (-8875 1725);
PAINT SKYBLUE (-8875 1725);
DISPLAY INVISIBLE (-8875 1725);
FORCEPROP 1 LAST PART_NUMBER TMP_QCS24702JB38
J 2
(-8575 1975);
DISPLAY 0.510638 (-8575 1975);
PAINT SKYBLUE (-8575 1975);
DISPLAY INVISIBLE (-8575 1975);
FORCEPROP 1 LAST TOLERANCE 5%
J 2
(-8750 1875);
DISPLAY 0.510638 (-8750 1875);
PAINT SKYBLUE (-8750 1875);
DISPLAY INVISIBLE (-8750 1875);
FORCEPROP 1 LAST MATERIAL CHIP
J 2
(-8725 1850);
DISPLAY 0.489362 (-8725 1850);
PAINT SKYBLUE (-8725 1850);
DISPLAY INVISIBLE (-8725 1850);
FORCEPROP 1 LAST WATTAGE 1/16W
J 0
(-8600 1725);
DISPLAY 0.510638 (-8600 1725);
PAINT SKYBLUE (-8600 1725);
DISPLAY INVISIBLE (-8600 1725);
FORCEPROP 1 LAST PATH I169
J 2
(-8575 2025);
DISPLAY 0.978723 (-8575 2025);
PAINT WHITE (-8575 2025);
DISPLAY INVISIBLE (-8575 2025);
FORCEPROP 2 LAST CDS_LIB pure_quanta
J 2
(-8625 1875);
DISPLAY INVISIBLE (-8625 1875);
FORCEADD OFFPAGE..2
(-1150 2175);
FORCEPROP 2 LAST $XR0 55 
J 0
(-961 2175);
DISPLAY 0.638298 (-961 2175);
PAINT MONO (-961 2175);
FORCEPROP 2 LAST PATH I17
J 0
(-975 2250);
DISPLAY 1.021277 (-975 2250);
DISPLAY INVISIBLE (-975 2250);
FORCEPROP 1 LAST COMMENT_BODY TRUE
J 0
(-1195 2080);
DISPLAY 0.872340 (-1195 2080);
PAINT GREEN (-1195 2080);
DISPLAY INVISIBLE (-1195 2080);
FORCEPROP 1 LAST OFFPAGE TRUE
J 0
(-825 2050);
DISPLAY 0.872340 (-825 2050);
PAINT GREEN (-825 2050);
DISPLAY INVISIBLE (-825 2050);
FORCEPROP 2 LAST CDS_LIB standard
J 2
(-1150 2175);
DISPLAY INVISIBLE (-1150 2175);
FORCEADD OFFPAGE..2
(-7625 1825);
FORCEPROP 2 LAST $XR1 55 
J 0
(-7346 1825);
DISPLAY 0.638298 (-7346 1825);
PAINT MONO (-7346 1825);
FORCEPROP 2 LAST $XR0 80 
J 0
(-7436 1825);
DISPLAY 0.638298 (-7436 1825);
PAINT MONO (-7436 1825);
FORCEPROP 2 LAST PATH I172
J 0
(-7450 1900);
DISPLAY 1.021277 (-7450 1900);
DISPLAY INVISIBLE (-7450 1900);
FORCEPROP 1 LAST COMMENT_BODY TRUE
J 0
(-7670 1730);
DISPLAY 0.872340 (-7670 1730);
PAINT GREEN (-7670 1730);
DISPLAY INVISIBLE (-7670 1730);
FORCEPROP 1 LAST OFFPAGE TRUE
J 0
(-7300 1700);
DISPLAY 0.872340 (-7300 1700);
PAINT GREEN (-7300 1700);
DISPLAY INVISIBLE (-7300 1700);
FORCEPROP 2 LAST CDS_LIB standard
J 0
(-7625 1825);
DISPLAY INVISIBLE (-7625 1825);
FORCEADD OFFPAGE..2
(-7625 1675);
FORCEPROP 2 LAST $XR1 80 
J 0
(-7346 1675);
DISPLAY 0.638298 (-7346 1675);
PAINT MONO (-7346 1675);
FORCEPROP 2 LAST $XR0 55 
J 0
(-7436 1675);
DISPLAY 0.638298 (-7436 1675);
PAINT MONO (-7436 1675);
FORCEPROP 2 LAST PATH I177
J 0
(-7450 1750);
DISPLAY 1.021277 (-7450 1750);
DISPLAY INVISIBLE (-7450 1750);
FORCEPROP 1 LAST COMMENT_BODY TRUE
J 0
(-7670 1580);
DISPLAY 0.872340 (-7670 1580);
PAINT GREEN (-7670 1580);
DISPLAY INVISIBLE (-7670 1580);
FORCEPROP 1 LAST OFFPAGE TRUE
J 0
(-7300 1550);
DISPLAY 0.872340 (-7300 1550);
PAINT GREEN (-7300 1550);
DISPLAY INVISIBLE (-7300 1550);
FORCEPROP 2 LAST CDS_LIB standard
J 0
(-7625 1675);
DISPLAY INVISIBLE (-7625 1675);
FORCEADD OFFPAGE..2
(-4500 2100);
FORCEPROP 2 LAST $XR0 55 
J 0
(-4311 2100);
DISPLAY 0.638298 (-4311 2100);
PAINT MONO (-4311 2100);
FORCEPROP 2 LAST PATH I18
J 0
(-4325 2175);
DISPLAY 1.021277 (-4325 2175);
DISPLAY INVISIBLE (-4325 2175);
FORCEPROP 1 LAST COMMENT_BODY TRUE
J 0
(-4545 2005);
DISPLAY 0.872340 (-4545 2005);
PAINT GREEN (-4545 2005);
DISPLAY INVISIBLE (-4545 2005);
FORCEPROP 1 LAST OFFPAGE TRUE
J 0
(-4175 1975);
DISPLAY 0.872340 (-4175 1975);
PAINT GREEN (-4175 1975);
DISPLAY INVISIBLE (-4175 1975);
FORCEPROP 2 LAST CDS_LIB standard
J 0
(-4500 2100);
DISPLAY INVISIBLE (-4500 2100);
FORCEADD OFFPAGE..2
(-7625 1775);
FORCEPROP 2 LAST $XR1 55 
J 0
(-7346 1775);
DISPLAY 0.638298 (-7346 1775);
PAINT MONO (-7346 1775);
FORCEPROP 2 LAST $XR0 80 
J 0
(-7436 1775);
DISPLAY 0.638298 (-7436 1775);
PAINT MONO (-7436 1775);
FORCEPROP 2 LAST PATH I180
J 0
(-7450 1850);
DISPLAY 1.021277 (-7450 1850);
DISPLAY INVISIBLE (-7450 1850);
FORCEPROP 1 LAST COMMENT_BODY TRUE
J 0
(-7670 1680);
DISPLAY 0.872340 (-7670 1680);
PAINT GREEN (-7670 1680);
DISPLAY INVISIBLE (-7670 1680);
FORCEPROP 1 LAST OFFPAGE TRUE
J 0
(-7300 1650);
DISPLAY 0.872340 (-7300 1650);
PAINT GREEN (-7300 1650);
DISPLAY INVISIBLE (-7300 1650);
FORCEPROP 2 LAST CDS_LIB standard
J 0
(-7625 1775);
DISPLAY INVISIBLE (-7625 1775);
FORCEADD GENOA_SP5..21
(-4375 4475);
FORCEPROP 1 LAST LOCATION U26
J 0
(-5470 6502);
DISPLAY 0.489362 (-5470 6502);
PAINT SKYBLUE (-5470 6502);
FORCEPROP 0 LAST $SEC 21
J 0
(-5450 6550);
DISPLAY 0.680851 (-5450 6550);
PAINT MONO (-5450 6550);
DISPLAY INVISIBLE (-5450 6550);
FORCEPROP 0 LAST CDS_SEC 21
J 0
(-5450 6175);
DISPLAY 1.021277 (-5450 6175);
DISPLAY INVISIBLE (-5450 6175);
FORCEPROP 0 LASTPIN (-5625 3475) $PN DE36
J 2
(-5635 3485);
DISPLAY 0.489362 (-5635 3485);
PAINT MONO (-5635 3485);
FORCEPROP 0 LASTPIN (-5625 3425) $PN DF36
J 2
(-5635 3435);
DISPLAY 0.489362 (-5635 3435);
PAINT MONO (-5635 3435);
FORCEPROP 0 LASTPIN (-5625 3375) $PN DF40
J 2
(-5635 3385);
DISPLAY 0.489362 (-5635 3385);
PAINT MONO (-5635 3385);
FORCEPROP 0 LASTPIN (-5625 3325) $PN DE40
J 2
(-5635 3335);
DISPLAY 0.489362 (-5635 3335);
PAINT MONO (-5635 3335);
FORCEPROP 0 LASTPIN (-5625 2725) $PN DH4
J 2
(-5635 2735);
DISPLAY 0.489362 (-5635 2735);
PAINT MONO (-5635 2735);
FORCEPROP 0 LASTPIN (-5625 3175) $PN DF33
J 2
(-5635 3185);
DISPLAY 0.489362 (-5635 3185);
PAINT MONO (-5635 3185);
FORCEPROP 0 LASTPIN (-5625 3125) $PN DE32
J 2
(-5635 3135);
DISPLAY 0.489362 (-5635 3135);
PAINT MONO (-5635 3135);
FORCEPROP 0 LASTPIN (-5625 3075) $PN DG11
J 2
(-5635 3085);
DISPLAY 0.489362 (-5635 3085);
PAINT MONO (-5635 3085);
FORCEPROP 0 LASTPIN (-5625 3025) $PN DJ29
J 2
(-5635 3035);
DISPLAY 0.489362 (-5635 3035);
PAINT MONO (-5635 3035);
FORCEPROP 0 LASTPIN (-5625 2975) $PN DH30
J 2
(-5635 2985);
DISPLAY 0.489362 (-5635 2985);
PAINT MONO (-5635 2985);
FORCEPROP 0 LASTPIN (-5625 2925) $PN DE30
J 2
(-5635 2935);
DISPLAY 0.489362 (-5635 2935);
PAINT MONO (-5635 2935);
FORCEPROP 0 LASTPIN (-5625 2875) $PN DF31
J 2
(-5635 2885);
DISPLAY 0.489362 (-5635 2885);
PAINT MONO (-5635 2885);
FORCEPROP 0 LASTPIN (-5625 2825) $PN DG31
J 2
(-5635 2835);
DISPLAY 0.489362 (-5635 2835);
PAINT MONO (-5635 2835);
FORCEPROP 0 LASTPIN (-5625 2775) $PN DG32
J 2
(-5635 2785);
DISPLAY 0.489362 (-5635 2785);
PAINT MONO (-5635 2785);
FORCEPROP 0 LASTPIN (-5625 3275) $PN DH16
J 2
(-5635 3285);
DISPLAY 0.489362 (-5635 3285);
PAINT MONO (-5635 3285);
FORCEPROP 0 LASTPIN (-5625 3225) $PN DH15
J 2
(-5635 3235);
DISPLAY 0.489362 (-5635 3235);
PAINT MONO (-5635 3235);
FORCEPROP 0 LASTPIN (-3125 2975) $PN A14
J 0
(-3115 2985);
DISPLAY 0.489362 (-3115 2985);
PAINT MONO (-3115 2985);
FORCEPROP 0 LASTPIN (-3125 2925) $PN C14
J 0
(-3115 2935);
DISPLAY 0.489362 (-3115 2935);
PAINT MONO (-3115 2935);
FORCEPROP 0 LASTPIN (-3125 2875) $PN A13
J 0
(-3115 2885);
DISPLAY 0.489362 (-3115 2885);
PAINT MONO (-3115 2885);
FORCEPROP 0 LASTPIN (-3125 2825) $PN B16
J 0
(-3115 2835);
DISPLAY 0.489362 (-3115 2835);
PAINT MONO (-3115 2835);
FORCEPROP 0 LASTPIN (-3125 5425) $PN B63
J 0
(-3115 5435);
DISPLAY 0.489362 (-3115 5435);
PAINT MONO (-3115 5435);
FORCEPROP 0 LASTPIN (-5625 4875) $PN DJ35
J 2
(-5635 4885);
DISPLAY 0.489362 (-5635 4885);
PAINT MONO (-5635 4885);
FORCEPROP 0 LASTPIN (-3125 4875) $PN A7
J 0
(-3115 4885);
DISPLAY 0.489362 (-3115 4885);
PAINT MONO (-3115 4885);
FORCEPROP 0 LASTPIN (-3125 4925) $PN A8
J 0
(-3115 4935);
DISPLAY 0.489362 (-3115 4935);
PAINT MONO (-3115 4935);
FORCEPROP 0 LASTPIN (-3125 4725) $PN C6
J 0
(-3115 4735);
DISPLAY 0.489362 (-3115 4735);
PAINT MONO (-3115 4735);
FORCEPROP 0 LASTPIN (-3125 4775) $PN B6
J 0
(-3115 4785);
DISPLAY 0.489362 (-3115 4785);
PAINT MONO (-3115 4785);
FORCEPROP 0 LASTPIN (-3125 4575) $PN A11
J 0
(-3115 4585);
DISPLAY 0.489362 (-3115 4585);
PAINT MONO (-3115 4585);
FORCEPROP 0 LASTPIN (-3125 4625) $PN A10
J 0
(-3115 4635);
DISPLAY 0.489362 (-3115 4635);
PAINT MONO (-3115 4635);
FORCEPROP 0 LASTPIN (-3125 4425) $PN C12
J 0
(-3115 4435);
DISPLAY 0.489362 (-3115 4435);
PAINT MONO (-3115 4435);
FORCEPROP 0 LASTPIN (-3125 4475) $PN B12
J 0
(-3115 4485);
DISPLAY 0.489362 (-3115 4485);
PAINT MONO (-3115 4485);
FORCEPROP 0 LASTPIN (-3125 4275) $PN C9
J 0
(-3115 4285);
DISPLAY 0.489362 (-3115 4285);
PAINT MONO (-3115 4285);
FORCEPROP 0 LASTPIN (-3125 4325) $PN B9
J 0
(-3115 4335);
DISPLAY 0.489362 (-3115 4335);
PAINT MONO (-3115 4335);
FORCEPROP 0 LASTPIN (-3125 4125) $PN DJ42
J 0
(-3115 4135);
DISPLAY 0.489362 (-3115 4135);
PAINT MONO (-3115 4135);
FORCEPROP 0 LASTPIN (-3125 4175) $PN DJ41
J 0
(-3115 4185);
DISPLAY 0.489362 (-3115 4185);
PAINT MONO (-3115 4185);
FORCEPROP 0 LASTPIN (-3125 3975) $PN DJ44
J 0
(-3115 3985);
DISPLAY 0.489362 (-3115 3985);
PAINT MONO (-3115 3985);
FORCEPROP 0 LASTPIN (-3125 4025) $PN DJ45
J 0
(-3115 4035);
DISPLAY 0.489362 (-3115 4035);
PAINT MONO (-3115 4035);
FORCEPROP 0 LASTPIN (-3125 3825) $PN DJ54
J 0
(-3115 3835);
DISPLAY 0.489362 (-3115 3835);
PAINT MONO (-3115 3835);
FORCEPROP 0 LASTPIN (-3125 3875) $PN DJ53
J 0
(-3115 3885);
DISPLAY 0.489362 (-3115 3885);
PAINT MONO (-3115 3885);
FORCEPROP 0 LASTPIN (-3125 3675) $PN DJ47
J 0
(-3115 3685);
DISPLAY 0.489362 (-3115 3685);
PAINT MONO (-3115 3685);
FORCEPROP 0 LASTPIN (-3125 3725) $PN DJ48
J 0
(-3115 3735);
DISPLAY 0.489362 (-3115 3735);
PAINT MONO (-3115 3735);
FORCEPROP 0 LASTPIN (-3125 3525) $PN DJ50
J 0
(-3115 3535);
DISPLAY 0.489362 (-3115 3535);
PAINT MONO (-3115 3535);
FORCEPROP 0 LASTPIN (-3125 3575) $PN DJ51
J 0
(-3115 3585);
DISPLAY 0.489362 (-3115 3585);
PAINT MONO (-3115 3585);
FORCEPROP 0 LASTPIN (-5625 4025) $PN DG12
J 2
(-5635 4035);
DISPLAY 0.489362 (-5635 4035);
PAINT MONO (-5635 4035);
FORCEPROP 0 LASTPIN (-5625 3975) $PN DH12
J 2
(-5635 3985);
DISPLAY 0.489362 (-5635 3985);
PAINT MONO (-5635 3985);
FORCEPROP 0 LASTPIN (-5625 3925) $PN DJ21
J 2
(-5635 3935);
DISPLAY 0.489362 (-5635 3935);
PAINT MONO (-5635 3935);
FORCEPROP 0 LASTPIN (-5625 3875) $PN DJ20
J 2
(-5635 3885);
DISPLAY 0.489362 (-5635 3885);
PAINT MONO (-5635 3885);
FORCEPROP 0 LASTPIN (-5625 4425) $PN A71
J 2
(-5635 4435);
DISPLAY 0.489362 (-5635 4435);
PAINT MONO (-5635 4435);
FORCEPROP 0 LASTPIN (-5625 4375) $PN B71
J 2
(-5635 4385);
DISPLAY 0.489362 (-5635 4385);
PAINT MONO (-5635 4385);
FORCEPROP 0 LASTPIN (-5625 4325) $PN C7
J 2
(-5635 4335);
DISPLAY 0.489362 (-5635 4335);
PAINT MONO (-5635 4335);
FORCEPROP 0 LASTPIN (-5625 4275) $PN A5
J 2
(-5635 4285);
DISPLAY 0.489362 (-5635 4285);
PAINT MONO (-5635 4285);
FORCEPROP 0 LASTPIN (-5625 4225) $PN C72
J 2
(-5635 4235);
DISPLAY 0.489362 (-5635 4235);
PAINT MONO (-5635 4235);
FORCEPROP 0 LASTPIN (-5625 4175) $PN B72
J 2
(-5635 4185);
DISPLAY 0.489362 (-5635 4185);
PAINT MONO (-5635 4185);
FORCEPROP 0 LASTPIN (-5625 4125) $PN A4
J 2
(-5635 4135);
DISPLAY 0.489362 (-5635 4135);
PAINT MONO (-5635 4135);
FORCEPROP 0 LASTPIN (-5625 4075) $PN B4
J 2
(-5635 4085);
DISPLAY 0.489362 (-5635 4085);
PAINT MONO (-5635 4085);
FORCEPROP 0 LASTPIN (-5625 4675) $PN DJ31
J 2
(-5635 4685);
DISPLAY 0.489362 (-5635 4685);
PAINT MONO (-5635 4685);
FORCEPROP 0 LASTPIN (-3125 5325) $PN B64
J 0
(-3115 5335);
DISPLAY 0.489362 (-3115 5335);
PAINT MONO (-3115 5335);
FORCEPROP 0 LASTPIN (-3125 5175) $PN D18
J 0
(-3115 5185);
DISPLAY 0.489362 (-3115 5185);
PAINT MONO (-3115 5185);
FORCEPROP 0 LASTPIN (-3125 5125) $PN DG36
J 0
(-3115 5135);
DISPLAY 0.489362 (-3115 5135);
PAINT MONO (-3115 5135);
FORCEPROP 0 LASTPIN (-5625 5625) $PN DH7
J 2
(-5635 5635);
DISPLAY 0.489362 (-5635 5635);
PAINT MONO (-5635 5635);
FORCEPROP 0 LASTPIN (-5625 5425) $PN DJ8
J 2
(-5635 5435);
DISPLAY 0.489362 (-5635 5435);
PAINT MONO (-5635 5435);
FORCEPROP 0 LASTPIN (-3125 5625) $PN DH36
J 0
(-3115 5635);
DISPLAY 0.489362 (-3115 5635);
PAINT MONO (-3115 5635);
FORCEPROP 0 LASTPIN (-3125 5775) $PN D69
J 0
(-3115 5785);
DISPLAY 0.489362 (-3115 5785);
PAINT MONO (-3115 5785);
FORCEPROP 0 LASTPIN (-3125 6075) $PN A20
J 0
(-3115 6085);
DISPLAY 0.489362 (-3115 6085);
PAINT MONO (-3115 6085);
FORCEPROP 0 LASTPIN (-3125 6125) $PN A19
J 0
(-3115 6135);
DISPLAY 0.489362 (-3115 6135);
PAINT MONO (-3115 6135);
FORCEPROP 0 LASTPIN (-3125 5875) $PN B67
J 0
(-3115 5885);
DISPLAY 0.489362 (-3115 5885);
PAINT MONO (-3115 5885);
FORCEPROP 0 LASTPIN (-5625 5525) $PN DG10
J 2
(-5635 5535);
DISPLAY 0.489362 (-5635 5535);
PAINT MONO (-5635 5535);
FORCEPROP 0 LASTPIN (-3125 5975) $PN DH9
J 0
(-3115 5985);
DISPLAY 0.489362 (-3115 5985);
PAINT MONO (-3115 5985);
FORCEPROP 0 LASTPIN (-3125 3175) $PN B14
J 0
(-3115 3185);
DISPLAY 0.489362 (-3115 3185);
PAINT MONO (-3115 3185);
FORCEPROP 0 LASTPIN (-3125 3125) $PN D14
J 0
(-3115 3135);
DISPLAY 0.489362 (-3115 3135);
PAINT MONO (-3115 3135);
FORCEPROP 0 LASTPIN (-5625 3625) $PN D15
J 2
(-5635 3635);
DISPLAY 0.489362 (-5635 3635);
PAINT MONO (-5635 3635);
FORCEPROP 0 LASTPIN (-5625 3575) $PN B15
J 2
(-5635 3585);
DISPLAY 0.489362 (-5635 3585);
PAINT MONO (-5635 3585);
FORCEPROP 0 LASTPIN (-5625 5725) $PN DJ5
J 2
(-5635 5735);
DISPLAY 0.489362 (-5635 5735);
PAINT MONO (-5635 5735);
FORCEPROP 0 LASTPIN (-5625 5775) $PN DG4
J 2
(-5635 5785);
DISPLAY 0.489362 (-5635 5785);
PAINT MONO (-5635 5785);
FORCEPROP 0 LASTPIN (-5625 3725) $PN DJ11
J 2
(-5635 3735);
DISPLAY 0.489362 (-5635 3735);
PAINT MONO (-5635 3735);
FORCEPROP 0 LASTPIN (-5625 5575) $PN DH6
J 2
(-5635 5585);
DISPLAY 0.489362 (-5635 5585);
PAINT MONO (-5635 5585);
FORCEPROP 0 LASTPIN (-3125 5525) $PN DJ10
J 0
(-3115 5535);
DISPLAY 0.489362 (-3115 5535);
PAINT MONO (-3115 5535);
FORCEPROP 0 LASTPIN (-5625 5075) $PN DJ14
J 2
(-5635 5085);
DISPLAY 0.489362 (-5635 5085);
PAINT MONO (-5635 5085);
FORCEPROP 0 LASTPIN (-5625 5025) $PN DJ13
J 2
(-5635 5035);
DISPLAY 0.489362 (-5635 5035);
PAINT MONO (-5635 5035);
FORCEPROP 0 LASTPIN (-5625 5275) $PN DJ17
J 2
(-5635 5285);
DISPLAY 0.489362 (-5635 5285);
PAINT MONO (-5635 5285);
FORCEPROP 0 LASTPIN (-5625 5225) $PN DJ16
J 2
(-5635 5235);
DISPLAY 0.489362 (-5635 5235);
PAINT MONO (-5635 5235);
FORCEPROP 1 LAST PART_NUMBER DGA^6000030
J 0
(-5470 6407);
DISPLAY 0.489362 (-5470 6407);
PAINT SKYBLUE (-5470 6407);
FORCEPROP 2 LAST VALUE SOCKET6096_13568-001
J 0
(-5450 6025);
DISPLAY 0.489362 (-5450 6025);
PAINT SKYBLUE (-5450 6025);
FORCEPROP 1 LAST MATERIAL IO
J 0
(-5470 6308);
DISPLAY 0.489362 (-5470 6308);
PAINT SKYBLUE (-5470 6308);
FORCEPROP 2 LAST PART_TYPE SMLF
J 0
(-5450 6125);
DISPLAY 1.021277 (-5450 6125);
FORCEPROP 1 LAST PATH I182
J 0
(-4375 4475);
DISPLAY 0.723404 (-4375 4475);
PAINT GREEN (-4375 4475);
DISPLAY INVISIBLE (-4375 4475);
FORCEPROP 2 LAST CDS_LIB pure_quanta
J 0
(-4375 4475);
DISPLAY INVISIBLE (-4375 4475);
FORCEPROP 1 LAST CDS_LMAN_SYM_OUTLINE -1100,1800,1100,-1800
J 0
(-4375 4475);
DISPLAY 0.468085 (-4375 4475);
PAINT GREEN (-4375 4475);
DISPLAY INVISIBLE (-4375 4475);
FORCEPROP 1 LAST NEEDS_NO_SIZE TRUE
J 0
(-4375 4475);
DISPLAY 0.723404 (-4375 4475);
PAINT GREEN (-4375 4475);
DISPLAY INVISIBLE (-4375 4475);
FORCEADD OFFPAGE..1
R 2
(-1000 5525);
FORCEPROP 2 LAST $XR1 28 
J 0
(-694 5525);
DISPLAY 0.638298 (-694 5525);
PAINT MONO (-694 5525);
FORCEPROP 2 LAST $XR0 132 
J 0
(-814 5525);
DISPLAY 0.638298 (-814 5525);
PAINT MONO (-814 5525);
FORCEPROP 2 LAST PATH I183
J 0
(-675 5575);
DISPLAY 1.021277 (-675 5575);
DISPLAY INVISIBLE (-675 5575);
FORCEPROP 1 LAST COMMENT_BODY TRUE
J 2
(-1125 5425);
DISPLAY 0.872340 (-1125 5425);
PAINT GREEN (-1125 5425);
DISPLAY INVISIBLE (-1125 5425);
FORCEPROP 1 LAST OFFPAGE TRUE
J 2
(-1325 5400);
DISPLAY 0.872340 (-1325 5400);
PAINT GREEN (-1325 5400);
DISPLAY INVISIBLE (-1325 5400);
FORCEPROP 2 LAST CDS_LIB standard
J 2
(-1000 5525);
DISPLAY INVISIBLE (-1000 5525);
FORCEADD OFFPAGE..1
R 2
(-2300 6125);
FORCEPROP 2 LAST $XR0 28 
J 0
(-2114 6125);
DISPLAY 0.638298 (-2114 6125);
PAINT MONO (-2114 6125);
FORCEPROP 2 LAST PATH I185
J 0
(-2100 6175);
DISPLAY 1.021277 (-2100 6175);
DISPLAY INVISIBLE (-2100 6175);
FORCEPROP 1 LAST COMMENT_BODY TRUE
J 2
(-2425 6025);
DISPLAY 0.872340 (-2425 6025);
PAINT GREEN (-2425 6025);
DISPLAY INVISIBLE (-2425 6025);
FORCEPROP 1 LAST OFFPAGE TRUE
J 2
(-2625 6000);
DISPLAY 0.872340 (-2625 6000);
PAINT GREEN (-2625 6000);
DISPLAY INVISIBLE (-2625 6000);
FORCEPROP 2 LAST CDS_LIB standard
J 2
(-2300 6125);
DISPLAY INVISIBLE (-2300 6125);
FORCEADD OFFPAGE..1
R 2
(-2300 6075);
FORCEPROP 2 LAST $XR0 28 
J 0
(-2114 6075);
DISPLAY 0.638298 (-2114 6075);
PAINT MONO (-2114 6075);
FORCEPROP 2 LAST PATH I186
J 0
(-2100 6125);
DISPLAY 1.021277 (-2100 6125);
DISPLAY INVISIBLE (-2100 6125);
FORCEPROP 1 LAST COMMENT_BODY TRUE
J 2
(-2425 5975);
DISPLAY 0.872340 (-2425 5975);
PAINT GREEN (-2425 5975);
DISPLAY INVISIBLE (-2425 5975);
FORCEPROP 1 LAST OFFPAGE TRUE
J 2
(-2625 5950);
DISPLAY 0.872340 (-2625 5950);
PAINT GREEN (-2625 5950);
DISPLAY INVISIBLE (-2625 5950);
FORCEPROP 2 LAST CDS_LIB standard
J 0
(-2300 6075);
DISPLAY INVISIBLE (-2300 6075);
FORCEADD OFFPAGE..3
(-2175 5775);
FORCEPROP 2 LAST $XR3 77 
J 0
(-1691 5775);
DISPLAY 0.638298 (-1691 5775);
PAINT MONO (-1691 5775);
FORCEPROP 2 LAST $XR2 84 
J 0
(-1781 5775);
DISPLAY 0.638298 (-1781 5775);
PAINT MONO (-1781 5775);
FORCEPROP 2 LAST $XR1 80 
J 0
(-1871 5775);
DISPLAY 0.638298 (-1871 5775);
PAINT MONO (-1871 5775);
FORCEPROP 2 LAST $XR0 55 
J 0
(-1961 5775);
DISPLAY 0.638298 (-1961 5775);
PAINT MONO (-1961 5775);
FORCEPROP 2 LAST PATH I187
J 0
(-1625 5825);
DISPLAY 1.021277 (-1625 5825);
DISPLAY INVISIBLE (-1625 5825);
FORCEPROP 1 LAST COMMENT_BODY TRUE
J 0
(-2225 5675);
DISPLAY 0.872340 (-2225 5675);
PAINT PEACH (-2225 5675);
DISPLAY INVISIBLE (-2225 5675);
FORCEPROP 1 LAST OFFPAGE TRUE
J 0
(-1850 5650);
DISPLAY 0.872340 (-1850 5650);
PAINT GREEN (-1850 5650);
DISPLAY INVISIBLE (-1850 5650);
FORCEPROP 2 LAST CDS_LIB standard
J 2
(-2175 5775);
DISPLAY INVISIBLE (-2175 5775);
FORCEADD OFFPAGE..3
(-2175 5875);
FORCEPROP 2 LAST $XR2 84 
J 0
(-1781 5875);
DISPLAY 0.638298 (-1781 5875);
PAINT MONO (-1781 5875);
FORCEPROP 2 LAST $XR1 80 
J 0
(-1871 5875);
DISPLAY 0.638298 (-1871 5875);
PAINT MONO (-1871 5875);
FORCEPROP 2 LAST $XR0 55 
J 0
(-1961 5875);
DISPLAY 0.638298 (-1961 5875);
PAINT MONO (-1961 5875);
FORCEPROP 2 LAST PATH I188
J 0
(-1750 5925);
DISPLAY 1.021277 (-1750 5925);
DISPLAY INVISIBLE (-1750 5925);
FORCEPROP 1 LAST COMMENT_BODY TRUE
J 0
(-2225 5775);
DISPLAY 0.872340 (-2225 5775);
PAINT PEACH (-2225 5775);
DISPLAY INVISIBLE (-2225 5775);
FORCEPROP 1 LAST OFFPAGE TRUE
J 0
(-1850 5750);
DISPLAY 0.872340 (-1850 5750);
PAINT GREEN (-1850 5750);
DISPLAY INVISIBLE (-1850 5750);
FORCEPROP 2 LAST CDS_LIB standard
J 2
(-2175 5875);
DISPLAY INVISIBLE (-2175 5875);
FORCEADD OFFPAGE..1
R 2
(-2300 5425);
FORCEPROP 2 LAST $XR1 80 
J 0
(-2024 5425);
DISPLAY 0.638298 (-2024 5425);
PAINT MONO (-2024 5425);
FORCEPROP 2 LAST $XR0 55 
J 0
(-2114 5425);
DISPLAY 0.638298 (-2114 5425);
PAINT MONO (-2114 5425);
FORCEPROP 2 LAST PATH I189
J 0
(-2000 5475);
DISPLAY 1.021277 (-2000 5475);
DISPLAY INVISIBLE (-2000 5475);
FORCEPROP 1 LAST COMMENT_BODY TRUE
J 2
(-2425 5325);
DISPLAY 0.872340 (-2425 5325);
PAINT GREEN (-2425 5325);
DISPLAY INVISIBLE (-2425 5325);
FORCEPROP 1 LAST OFFPAGE TRUE
J 2
(-2625 5300);
DISPLAY 0.872340 (-2625 5300);
PAINT GREEN (-2625 5300);
DISPLAY INVISIBLE (-2625 5300);
FORCEPROP 2 LAST CDS_LIB standard
J 0
(-2300 5425);
DISPLAY INVISIBLE (-2300 5425);
FORCEADD OFFPAGE..2
(-4500 2150);
FORCEPROP 2 LAST $XR0 55 
J 0
(-4311 2150);
DISPLAY 0.638298 (-4311 2150);
PAINT MONO (-4311 2150);
FORCEPROP 2 LAST PATH I19
J 0
(-4325 2225);
DISPLAY 1.021277 (-4325 2225);
DISPLAY INVISIBLE (-4325 2225);
FORCEPROP 1 LAST COMMENT_BODY TRUE
J 0
(-4545 2055);
DISPLAY 0.872340 (-4545 2055);
PAINT GREEN (-4545 2055);
DISPLAY INVISIBLE (-4545 2055);
FORCEPROP 1 LAST OFFPAGE TRUE
J 0
(-4175 2025);
DISPLAY 0.872340 (-4175 2025);
PAINT GREEN (-4175 2025);
DISPLAY INVISIBLE (-4175 2025);
FORCEPROP 2 LAST CDS_LIB standard
J 0
(-4500 2150);
DISPLAY INVISIBLE (-4500 2150);
FORCEADD OFFPAGE..2
(-2300 5625);
FORCEPROP 2 LAST $XR1 80 
J 0
(-2021 5625);
DISPLAY 0.638298 (-2021 5625);
PAINT MONO (-2021 5625);
FORCEPROP 2 LAST $XR0 55 
J 0
(-2111 5625);
DISPLAY 0.638298 (-2111 5625);
PAINT MONO (-2111 5625);
FORCEPROP 2 LAST PATH I190
J 0
(-1900 5675);
DISPLAY 1.021277 (-1900 5675);
DISPLAY INVISIBLE (-1900 5675);
FORCEPROP 1 LAST COMMENT_BODY TRUE
J 0
(-2345 5530);
DISPLAY 0.872340 (-2345 5530);
PAINT GREEN (-2345 5530);
DISPLAY INVISIBLE (-2345 5530);
FORCEPROP 1 LAST OFFPAGE TRUE
J 0
(-1975 5500);
DISPLAY 0.872340 (-1975 5500);
PAINT GREEN (-1975 5500);
DISPLAY INVISIBLE (-1975 5500);
FORCEPROP 2 LAST CDS_LIB standard
J 0
(-2300 5625);
DISPLAY INVISIBLE (-2300 5625);
FORCEADD OFFPAGE..2
(-2300 5325);
FORCEPROP 2 LAST $XR1 80 
J 0
(-2021 5325);
DISPLAY 0.638298 (-2021 5325);
PAINT MONO (-2021 5325);
FORCEPROP 2 LAST $XR0 55 
J 0
(-2111 5325);
DISPLAY 0.638298 (-2111 5325);
PAINT MONO (-2111 5325);
FORCEPROP 2 LAST PATH I191
J 0
(-2000 5375);
DISPLAY 1.021277 (-2000 5375);
DISPLAY INVISIBLE (-2000 5375);
FORCEPROP 1 LAST COMMENT_BODY TRUE
J 0
(-2345 5230);
DISPLAY 0.872340 (-2345 5230);
PAINT GREEN (-2345 5230);
DISPLAY INVISIBLE (-2345 5230);
FORCEPROP 1 LAST OFFPAGE TRUE
J 0
(-1975 5200);
DISPLAY 0.872340 (-1975 5200);
PAINT GREEN (-1975 5200);
DISPLAY INVISIBLE (-1975 5200);
FORCEPROP 2 LAST CDS_LIB standard
J 0
(-2300 5325);
DISPLAY INVISIBLE (-2300 5325);
FORCEADD OFFPAGE..2
(-2275 5175);
FORCEPROP 2 LAST $XR1 82 
J 0
(-1996 5175);
DISPLAY 0.638298 (-1996 5175);
PAINT MONO (-1996 5175);
FORCEPROP 2 LAST $XR0 80 
J 0
(-2086 5175);
DISPLAY 0.638298 (-2086 5175);
PAINT MONO (-2086 5175);
FORCEPROP 2 LAST PATH I192
J 0
(-1975 5225);
DISPLAY 1.021277 (-1975 5225);
DISPLAY INVISIBLE (-1975 5225);
FORCEPROP 1 LAST COMMENT_BODY TRUE
J 0
(-2320 5080);
DISPLAY 0.872340 (-2320 5080);
PAINT GREEN (-2320 5080);
DISPLAY INVISIBLE (-2320 5080);
FORCEPROP 1 LAST OFFPAGE TRUE
J 0
(-1950 5050);
DISPLAY 0.872340 (-1950 5050);
PAINT GREEN (-1950 5050);
DISPLAY INVISIBLE (-1950 5050);
FORCEPROP 2 LAST CDS_LIB standard
J 0
(-2275 5175);
DISPLAY INVISIBLE (-2275 5175);
FORCEADD OFFPAGE..2
(-2275 5125);
FORCEPROP 2 LAST $XR1 82 
J 0
(-1996 5125);
DISPLAY 0.638298 (-1996 5125);
PAINT MONO (-1996 5125);
FORCEPROP 2 LAST $XR0 80 
J 0
(-2086 5125);
DISPLAY 0.638298 (-2086 5125);
PAINT MONO (-2086 5125);
FORCEPROP 2 LAST PATH I193
J 0
(-1975 5175);
DISPLAY 1.021277 (-1975 5175);
DISPLAY INVISIBLE (-1975 5175);
FORCEPROP 1 LAST COMMENT_BODY TRUE
J 0
(-2320 5030);
DISPLAY 0.872340 (-2320 5030);
PAINT GREEN (-2320 5030);
DISPLAY INVISIBLE (-2320 5030);
FORCEPROP 1 LAST OFFPAGE TRUE
J 0
(-1950 5000);
DISPLAY 0.872340 (-1950 5000);
PAINT GREEN (-1950 5000);
DISPLAY INVISIBLE (-1950 5000);
FORCEPROP 2 LAST CDS_LIB standard
J 0
(-2275 5125);
DISPLAY INVISIBLE (-2275 5125);
FORCEADD UNIVERSAL_GND..1
(-6175 525);
FORCEPROP 3 LASTPIN (-6175 575) SIG_NAME GND\g
J 0
(-6165 585);
DISPLAY 0.659574 (-6165 585);
PAINT MONO (-6165 585);
DISPLAY INVISIBLE (-6165 585);
FORCEPROP 1 LAST HDL_POWER GND
J 1
(-6150 450);
DISPLAY 0.872340 (-6150 450);
PAINT GREEN (-6150 450);
DISPLAY INVISIBLE (-6150 450);
FORCEPROP 1 LAST PATH I2
J 0
(-6100 525);
DISPLAY 0.872340 (-6100 525);
PAINT AQUA (-6100 525);
DISPLAY INVISIBLE (-6100 525);
FORCEPROP 2 LAST CDS_LIB pure_quanta_power
J 0
(-6175 525);
DISPLAY INVISIBLE (-6175 525);
FORCEADD OFFPAGE..1
(-6425 5525);
FORCEPROP 2 LAST $XR1 80 
J 0
(-6736 5525);
DISPLAY 0.638298 (-6736 5525);
PAINT MONO (-6736 5525);
FORCEPROP 2 LAST $XR0 55 
J 0
(-6646 5525);
DISPLAY 0.638298 (-6646 5525);
PAINT MONO (-6646 5525);
FORCEPROP 2 LAST PATH I212
J 0
(-6675 5575);
DISPLAY 1.021277 (-6675 5575);
DISPLAY INVISIBLE (-6675 5575);
FORCEPROP 1 LAST COMMENT_BODY TRUE
J 0
(-6300 5425);
DISPLAY 0.872340 (-6300 5425);
PAINT GREEN (-6300 5425);
DISPLAY INVISIBLE (-6300 5425);
FORCEPROP 1 LAST OFFPAGE TRUE
J 0
(-6100 5400);
DISPLAY 0.872340 (-6100 5400);
PAINT GREEN (-6100 5400);
DISPLAY INVISIBLE (-6100 5400);
FORCEPROP 2 LAST CDS_LIB standard
J 0
(-6425 5525);
DISPLAY INVISIBLE (-6425 5525);
FORCEADD OFFPAGE..1
(-6425 5425);
FORCEPROP 2 LAST $XR1 80 
J 0
(-6736 5425);
DISPLAY 0.638298 (-6736 5425);
PAINT MONO (-6736 5425);
FORCEPROP 2 LAST $XR0 28 
J 0
(-6646 5425);
DISPLAY 0.638298 (-6646 5425);
PAINT MONO (-6646 5425);
FORCEPROP 2 LAST PATH I215
J 0
(-6675 5475);
DISPLAY 1.021277 (-6675 5475);
DISPLAY INVISIBLE (-6675 5475);
FORCEPROP 1 LAST COMMENT_BODY TRUE
J 0
(-6300 5325);
DISPLAY 0.872340 (-6300 5325);
PAINT GREEN (-6300 5325);
DISPLAY INVISIBLE (-6300 5325);
FORCEPROP 1 LAST OFFPAGE TRUE
J 0
(-6100 5300);
DISPLAY 0.872340 (-6100 5300);
PAINT GREEN (-6100 5300);
DISPLAY INVISIBLE (-6100 5300);
FORCEPROP 2 LAST CDS_LIB standard
J 0
(-6425 5425);
DISPLAY INVISIBLE (-6425 5425);
FORCEADD OFFPAGE..1
(-6425 5575);
FORCEPROP 2 LAST $XR1 80 
J 0
(-6736 5575);
DISPLAY 0.638298 (-6736 5575);
PAINT MONO (-6736 5575);
FORCEPROP 2 LAST $XR0 55 
J 0
(-6646 5575);
DISPLAY 0.638298 (-6646 5575);
PAINT MONO (-6646 5575);
FORCEPROP 2 LAST PATH I216
J 0
(-6675 5625);
DISPLAY 1.021277 (-6675 5625);
DISPLAY INVISIBLE (-6675 5625);
FORCEPROP 1 LAST COMMENT_BODY TRUE
J 0
(-6300 5475);
DISPLAY 0.872340 (-6300 5475);
PAINT GREEN (-6300 5475);
DISPLAY INVISIBLE (-6300 5475);
FORCEPROP 1 LAST OFFPAGE TRUE
J 0
(-6100 5450);
DISPLAY 0.872340 (-6100 5450);
PAINT GREEN (-6100 5450);
DISPLAY INVISIBLE (-6100 5450);
FORCEPROP 2 LAST CDS_LIB standard
J 0
(-6425 5575);
DISPLAY INVISIBLE (-6425 5575);
FORCEADD OFFPAGE..1
(-6425 5225);
FORCEPROP 2 LAST $XR0 55 
J 0
(-6646 5225);
DISPLAY 0.638298 (-6646 5225);
PAINT MONO (-6646 5225);
FORCEPROP 2 LAST PATH I217
J 0
(-6675 5275);
DISPLAY 1.021277 (-6675 5275);
DISPLAY INVISIBLE (-6675 5275);
FORCEPROP 1 LAST COMMENT_BODY TRUE
J 0
(-6300 5125);
DISPLAY 0.872340 (-6300 5125);
PAINT GREEN (-6300 5125);
DISPLAY INVISIBLE (-6300 5125);
FORCEPROP 1 LAST OFFPAGE TRUE
J 0
(-6100 5100);
DISPLAY 0.872340 (-6100 5100);
PAINT GREEN (-6100 5100);
DISPLAY INVISIBLE (-6100 5100);
FORCEPROP 2 LAST CDS_LIB standard
J 0
(-6425 5225);
DISPLAY INVISIBLE (-6425 5225);
FORCEADD OFFPAGE..1
(-6425 5275);
FORCEPROP 2 LAST $XR0 55 
J 0
(-6646 5275);
DISPLAY 0.638298 (-6646 5275);
PAINT MONO (-6646 5275);
FORCEPROP 2 LAST PATH I218
J 0
(-6675 5325);
DISPLAY 1.021277 (-6675 5325);
DISPLAY INVISIBLE (-6675 5325);
FORCEPROP 1 LAST COMMENT_BODY TRUE
J 0
(-6300 5175);
DISPLAY 0.872340 (-6300 5175);
PAINT GREEN (-6300 5175);
DISPLAY INVISIBLE (-6300 5175);
FORCEPROP 1 LAST OFFPAGE TRUE
J 0
(-6100 5150);
DISPLAY 0.872340 (-6100 5150);
PAINT GREEN (-6100 5150);
DISPLAY INVISIBLE (-6100 5150);
FORCEPROP 2 LAST CDS_LIB standard
J 0
(-6425 5275);
DISPLAY INVISIBLE (-6425 5275);
FORCEADD OFFPAGE..1
(-6425 4675);
FORCEPROP 2 LAST $XR1 80 
J 0
(-6736 4675);
DISPLAY 0.638298 (-6736 4675);
PAINT MONO (-6736 4675);
FORCEPROP 2 LAST $XR0 55 
J 0
(-6646 4675);
DISPLAY 0.638298 (-6646 4675);
PAINT MONO (-6646 4675);
FORCEPROP 2 LAST PATH I219
J 0
(-6675 4725);
DISPLAY 1.021277 (-6675 4725);
DISPLAY INVISIBLE (-6675 4725);
FORCEPROP 1 LAST COMMENT_BODY TRUE
J 0
(-6300 4575);
DISPLAY 0.872340 (-6300 4575);
PAINT GREEN (-6300 4575);
DISPLAY INVISIBLE (-6300 4575);
FORCEPROP 1 LAST OFFPAGE TRUE
J 0
(-6100 4550);
DISPLAY 0.872340 (-6100 4550);
PAINT GREEN (-6100 4550);
DISPLAY INVISIBLE (-6100 4550);
FORCEPROP 2 LAST CDS_LIB standard
J 0
(-6425 4675);
DISPLAY INVISIBLE (-6425 4675);
FORCEADD OFFPAGE..1
(-6425 5025);
FORCEPROP 2 LAST $XR0 55 
J 0
(-6646 5025);
DISPLAY 0.638298 (-6646 5025);
PAINT MONO (-6646 5025);
FORCEPROP 2 LAST PATH I220
J 0
(-6675 5075);
DISPLAY 1.021277 (-6675 5075);
DISPLAY INVISIBLE (-6675 5075);
FORCEPROP 1 LAST COMMENT_BODY TRUE
J 0
(-6300 4925);
DISPLAY 0.872340 (-6300 4925);
PAINT GREEN (-6300 4925);
DISPLAY INVISIBLE (-6300 4925);
FORCEPROP 1 LAST OFFPAGE TRUE
J 0
(-6100 4900);
DISPLAY 0.872340 (-6100 4900);
PAINT GREEN (-6100 4900);
DISPLAY INVISIBLE (-6100 4900);
FORCEPROP 2 LAST CDS_LIB standard
J 0
(-6425 5025);
DISPLAY INVISIBLE (-6425 5025);
FORCEADD OFFPAGE..1
(-6425 5075);
FORCEPROP 2 LAST $XR0 55 
J 0
(-6646 5075);
DISPLAY 0.638298 (-6646 5075);
PAINT MONO (-6646 5075);
FORCEPROP 2 LAST PATH I221
J 0
(-6675 5125);
DISPLAY 1.021277 (-6675 5125);
DISPLAY INVISIBLE (-6675 5125);
FORCEPROP 1 LAST COMMENT_BODY TRUE
J 0
(-6300 4975);
DISPLAY 0.872340 (-6300 4975);
PAINT GREEN (-6300 4975);
DISPLAY INVISIBLE (-6300 4975);
FORCEPROP 1 LAST OFFPAGE TRUE
J 0
(-6100 4950);
DISPLAY 0.872340 (-6100 4950);
PAINT GREEN (-6100 4950);
DISPLAY INVISIBLE (-6100 4950);
FORCEPROP 2 LAST CDS_LIB standard
J 0
(-6425 5075);
DISPLAY INVISIBLE (-6425 5075);
FORCEADD OFFPAGE..2
R 2
(-6425 3725);
FORCEPROP 2 LAST $XR1 80 
J 0
(-6739 3725);
DISPLAY 0.638298 (-6739 3725);
PAINT MONO (-6739 3725);
FORCEPROP 2 LAST $XR0 55 
J 0
(-6649 3725);
DISPLAY 0.638298 (-6649 3725);
PAINT MONO (-6649 3725);
FORCEPROP 2 LAST PATH I230
J 0
(-6625 3775);
DISPLAY 1.021277 (-6625 3775);
DISPLAY INVISIBLE (-6625 3775);
FORCEPROP 1 LAST COMMENT_BODY TRUE
J 2
(-6380 3630);
DISPLAY 0.872340 (-6380 3630);
PAINT GREEN (-6380 3630);
DISPLAY INVISIBLE (-6380 3630);
FORCEPROP 1 LAST OFFPAGE TRUE
J 2
(-6750 3600);
DISPLAY 0.872340 (-6750 3600);
PAINT GREEN (-6750 3600);
DISPLAY INVISIBLE (-6750 3600);
FORCEPROP 2 LAST CDS_LIB standard
J 0
(-6425 3725);
DISPLAY INVISIBLE (-6425 3725);
FORCEADD OFFPAGE..3
R 2
(-6650 3375);
FORCEPROP 2 LAST $XR1 81 
J 0
(-6989 3375);
DISPLAY 0.638298 (-6989 3375);
PAINT MONO (-6989 3375);
FORCEPROP 2 LAST $XR0 55 
J 0
(-6899 3375);
DISPLAY 0.638298 (-6899 3375);
PAINT MONO (-6899 3375);
FORCEPROP 2 LAST PATH I231
J 0
(-6925 3425);
DISPLAY 1.021277 (-6925 3425);
DISPLAY INVISIBLE (-6925 3425);
FORCEPROP 1 LAST COMMENT_BODY TRUE
J 2
(-6600 3275);
DISPLAY 0.872340 (-6600 3275);
PAINT PEACH (-6600 3275);
DISPLAY INVISIBLE (-6600 3275);
FORCEPROP 1 LAST OFFPAGE TRUE
J 2
(-6975 3250);
DISPLAY 0.872340 (-6975 3250);
PAINT GREEN (-6975 3250);
DISPLAY INVISIBLE (-6975 3250);
FORCEPROP 2 LAST CDS_LIB standard
J 0
(-6650 3375);
DISPLAY INVISIBLE (-6650 3375);
FORCEADD OFFPAGE..3
R 2
(-6650 3325);
FORCEPROP 2 LAST $XR1 81 
J 0
(-6989 3325);
DISPLAY 0.638298 (-6989 3325);
PAINT MONO (-6989 3325);
FORCEPROP 2 LAST $XR0 55 
J 0
(-6899 3325);
DISPLAY 0.638298 (-6899 3325);
PAINT MONO (-6899 3325);
FORCEPROP 2 LAST PATH I232
J 0
(-6925 3375);
DISPLAY 1.021277 (-6925 3375);
DISPLAY INVISIBLE (-6925 3375);
FORCEPROP 1 LAST COMMENT_BODY TRUE
J 2
(-6600 3225);
DISPLAY 0.872340 (-6600 3225);
PAINT PEACH (-6600 3225);
DISPLAY INVISIBLE (-6600 3225);
FORCEPROP 1 LAST OFFPAGE TRUE
J 2
(-6975 3200);
DISPLAY 0.872340 (-6975 3200);
PAINT GREEN (-6975 3200);
DISPLAY INVISIBLE (-6975 3200);
FORCEPROP 2 LAST CDS_LIB standard
J 0
(-6650 3325);
DISPLAY INVISIBLE (-6650 3325);
FORCEADD OFFPAGE..3
R 2
(-6650 3275);
FORCEPROP 2 LAST $XR1 81 
J 0
(-6989 3275);
DISPLAY 0.638298 (-6989 3275);
PAINT MONO (-6989 3275);
FORCEPROP 2 LAST $XR0 55 
J 0
(-6899 3275);
DISPLAY 0.638298 (-6899 3275);
PAINT MONO (-6899 3275);
FORCEPROP 2 LAST PATH I233
J 0
(-6925 3325);
DISPLAY 1.021277 (-6925 3325);
DISPLAY INVISIBLE (-6925 3325);
FORCEPROP 1 LAST COMMENT_BODY TRUE
J 2
(-6600 3175);
DISPLAY 0.872340 (-6600 3175);
PAINT PEACH (-6600 3175);
DISPLAY INVISIBLE (-6600 3175);
FORCEPROP 1 LAST OFFPAGE TRUE
J 2
(-6975 3150);
DISPLAY 0.872340 (-6975 3150);
PAINT GREEN (-6975 3150);
DISPLAY INVISIBLE (-6975 3150);
FORCEPROP 2 LAST CDS_LIB standard
J 0
(-6650 3275);
DISPLAY INVISIBLE (-6650 3275);
FORCEADD OFFPAGE..3
R 2
(-6650 3225);
FORCEPROP 2 LAST $XR1 81 
J 0
(-6989 3225);
DISPLAY 0.638298 (-6989 3225);
PAINT MONO (-6989 3225);
FORCEPROP 2 LAST $XR0 55 
J 0
(-6899 3225);
DISPLAY 0.638298 (-6899 3225);
PAINT MONO (-6899 3225);
FORCEPROP 2 LAST PATH I234
J 0
(-6925 3275);
DISPLAY 1.021277 (-6925 3275);
DISPLAY INVISIBLE (-6925 3275);
FORCEPROP 1 LAST COMMENT_BODY TRUE
J 2
(-6600 3125);
DISPLAY 0.872340 (-6600 3125);
PAINT PEACH (-6600 3125);
DISPLAY INVISIBLE (-6600 3125);
FORCEPROP 1 LAST OFFPAGE TRUE
J 2
(-6975 3100);
DISPLAY 0.872340 (-6975 3100);
PAINT GREEN (-6975 3100);
DISPLAY INVISIBLE (-6975 3100);
FORCEPROP 2 LAST CDS_LIB standard
J 0
(-6650 3225);
DISPLAY INVISIBLE (-6650 3225);
FORCEADD Q_RES..1
(-6900 3475);
FORCEPROP 1 LAST LOCATION R570
J 0
(-7125 3475);
DISPLAY 0.489362 (-7125 3475);
PAINT SKYBLUE (-7125 3475);
FORCEPROP 0 LAST $SEC 1
J 0
(-7175 3525);
DISPLAY 0.680851 (-7175 3525);
PAINT MONO (-7175 3525);
DISPLAY INVISIBLE (-7175 3525);
FORCEPROP 0 LAST CDS_SEC 1
J 0
(-7175 3525);
DISPLAY 1.021277 (-7175 3525);
DISPLAY INVISIBLE (-7175 3525);
FORCEPROP 1 LASTPIN (-7000 3475) $PN 1
J 0
(-6988 3487);
DISPLAY 0.489362 (-6988 3487);
PAINT MONO (-6988 3487);
FORCEPROP 1 LASTPIN (-6800 3475) $PN 2
J 0
(-6838 3487);
DISPLAY 0.489362 (-6838 3487);
PAINT MONO (-6838 3487);
FORCEPROP 1 LAST VALUE 0
J 2
(-6750 3475);
DISPLAY 0.489362 (-6750 3475);
PAINT SKYBLUE (-6750 3475);
FORCEPROP 1 LAST PACK_TYPE 0402LF
J 0
(-6850 3400);
DISPLAY 0.489362 (-6850 3400);
PAINT SKYBLUE (-6850 3400);
DISPLAY INVISIBLE (-6850 3400);
FORCEPROP 1 LAST PART_NUMBER CS00002JB38
J 0
(-6875 3525);
DISPLAY 0.489362 (-6875 3525);
PAINT SKYBLUE (-6875 3525);
DISPLAY INVISIBLE (-6875 3525);
FORCEPROP 1 LAST TOLERANCE 5%
J 0
(-6925 3400);
DISPLAY 0.489362 (-6925 3400);
PAINT SKYBLUE (-6925 3400);
DISPLAY INVISIBLE (-6925 3400);
FORCEPROP 1 LAST MATERIAL CHIP
J 0
(-6475 3400);
DISPLAY 0.489362 (-6475 3400);
PAINT SKYBLUE (-6475 3400);
DISPLAY INVISIBLE (-6475 3400);
FORCEPROP 1 LAST WATTAGE 1/16W
J 2
(-6500 3400);
DISPLAY 0.489362 (-6500 3400);
PAINT SKYBLUE (-6500 3400);
DISPLAY INVISIBLE (-6500 3400);
FORCEPROP 1 LAST PATH I236
J 0
(-6950 3625);
DISPLAY 0.978723 (-6950 3625);
PAINT WHITE (-6950 3625);
DISPLAY INVISIBLE (-6950 3625);
FORCEPROP 2 LAST CDS_LIB pure_quanta
J 0
(-6900 3475);
DISPLAY INVISIBLE (-6900 3475);
FORCEADD Q_RES..1
(-2250 2175);
FORCEPROP 1 LAST LOCATION R574
J 0
(-2575 2175);
DISPLAY 0.489362 (-2575 2175);
PAINT SKYBLUE (-2575 2175);
FORCEPROP 0 LAST $SEC 1
J 0
(-2425 2350);
DISPLAY 0.680851 (-2425 2350);
PAINT MONO (-2425 2350);
DISPLAY INVISIBLE (-2425 2350);
FORCEPROP 0 LAST CDS_SEC 1
J 0
(-2425 2350);
DISPLAY 1.021277 (-2425 2350);
DISPLAY INVISIBLE (-2425 2350);
FORCEPROP 1 LASTPIN (-2350 2175) $PN 1
J 0
(-2338 2187);
DISPLAY 0.489362 (-2338 2187);
PAINT MONO (-2338 2187);
FORCEPROP 1 LASTPIN (-2150 2175) $PN 2
J 0
(-2188 2187);
DISPLAY 0.489362 (-2188 2187);
PAINT MONO (-2188 2187);
FORCEPROP 1 LAST VALUE 0
J 2
(-2050 2175);
DISPLAY 0.489362 (-2050 2175);
PAINT SKYBLUE (-2050 2175);
FORCEPROP 1 LAST MATERIAL EMPTY
J 0
(-2450 2175);
DISPLAY 0.489362 (-2450 2175);
PAINT RED (-2450 2175);
FORCEPROP 1 LAST PACK_TYPE 0402LF
J 0
(-1800 2250);
DISPLAY 0.489362 (-1800 2250);
PAINT SKYBLUE (-1800 2250);
DISPLAY INVISIBLE (-1800 2250);
FORCEPROP 1 LAST PART_NUMBER CS00002JB38
J 0
(-2425 2300);
DISPLAY 0.489362 (-2425 2300);
PAINT SKYBLUE (-2425 2300);
DISPLAY INVISIBLE (-2425 2300);
FORCEPROP 1 LAST TOLERANCE 5%
J 0
(-2425 2250);
DISPLAY 0.489362 (-2425 2250);
PAINT SKYBLUE (-2425 2250);
DISPLAY INVISIBLE (-2425 2250);
FORCEPROP 1 LAST WATTAGE 1/16W
J 2
(-2075 2250);
DISPLAY 0.489362 (-2075 2250);
PAINT SKYBLUE (-2075 2250);
DISPLAY INVISIBLE (-2075 2250);
FORCEPROP 1 LAST PATH I24
J 0
(-2300 2325);
DISPLAY 0.978723 (-2300 2325);
PAINT WHITE (-2300 2325);
DISPLAY INVISIBLE (-2300 2325);
FORCEPROP 2 LAST CDS_LIB pure_quanta
J 0
(-2250 2175);
DISPLAY INVISIBLE (-2250 2175);
FORCEADD OFFPAGE..2
R 2
(-7900 3475);
FORCEPROP 2 LAST $XR1 80 
J 0
(-8214 3475);
DISPLAY 0.638298 (-8214 3475);
PAINT MONO (-8214 3475);
FORCEPROP 2 LAST $XR0 55 
J 0
(-8124 3475);
DISPLAY 0.638298 (-8124 3475);
PAINT MONO (-8124 3475);
FORCEPROP 2 LAST PATH I241
J 0
(-8150 3525);
DISPLAY 1.021277 (-8150 3525);
DISPLAY INVISIBLE (-8150 3525);
FORCEPROP 1 LAST COMMENT_BODY TRUE
J 2
(-7855 3380);
DISPLAY 0.872340 (-7855 3380);
PAINT GREEN (-7855 3380);
DISPLAY INVISIBLE (-7855 3380);
FORCEPROP 1 LAST OFFPAGE TRUE
J 2
(-8225 3350);
DISPLAY 0.872340 (-8225 3350);
PAINT GREEN (-8225 3350);
DISPLAY INVISIBLE (-8225 3350);
FORCEPROP 2 LAST CDS_LIB standard
J 2
(-7900 3475);
DISPLAY INVISIBLE (-7900 3475);
FORCEADD OFFPAGE..2
(-7625 2750);
FORCEPROP 2 LAST $XR1 136 
J 0
(-7346 2750);
DISPLAY 0.638298 (-7346 2750);
PAINT MONO (-7346 2750);
FORCEPROP 2 LAST $XR0 55 
J 0
(-7436 2750);
DISPLAY 0.638298 (-7436 2750);
PAINT MONO (-7436 2750);
FORCEPROP 2 LAST PATH I242
J 0
(-7325 2800);
DISPLAY 1.021277 (-7325 2800);
DISPLAY INVISIBLE (-7325 2800);
FORCEPROP 1 LAST COMMENT_BODY TRUE
J 0
(-7670 2655);
DISPLAY 0.872340 (-7670 2655);
PAINT PEACH (-7670 2655);
DISPLAY INVISIBLE (-7670 2655);
FORCEPROP 1 LAST OFFPAGE TRUE
J 0
(-7300 2625);
DISPLAY 0.872340 (-7300 2625);
PAINT GREEN (-7300 2625);
DISPLAY INVISIBLE (-7300 2625);
FORCEPROP 2 LAST CDS_LIB standard
J 0
(-7625 2750);
DISPLAY INVISIBLE (-7625 2750);
FORCEADD OFFPAGE..2
(-7625 2700);
FORCEPROP 2 LAST $XR1 136 
J 0
(-7346 2700);
DISPLAY 0.638298 (-7346 2700);
PAINT MONO (-7346 2700);
FORCEPROP 2 LAST $XR0 55 
J 0
(-7436 2700);
DISPLAY 0.638298 (-7436 2700);
PAINT MONO (-7436 2700);
FORCEPROP 2 LAST PATH I243
J 0
(-7325 2750);
DISPLAY 1.021277 (-7325 2750);
DISPLAY INVISIBLE (-7325 2750);
FORCEPROP 1 LAST COMMENT_BODY TRUE
J 0
(-7670 2605);
DISPLAY 0.872340 (-7670 2605);
PAINT PEACH (-7670 2605);
DISPLAY INVISIBLE (-7670 2605);
FORCEPROP 1 LAST OFFPAGE TRUE
J 0
(-7300 2575);
DISPLAY 0.872340 (-7300 2575);
PAINT GREEN (-7300 2575);
DISPLAY INVISIBLE (-7300 2575);
FORCEPROP 2 LAST CDS_LIB standard
J 0
(-7625 2700);
DISPLAY INVISIBLE (-7625 2700);
FORCEADD OFFPAGE..2
(-7625 2650);
FORCEPROP 2 LAST $XR1 136 
J 0
(-7346 2650);
DISPLAY 0.638298 (-7346 2650);
PAINT MONO (-7346 2650);
FORCEPROP 2 LAST $XR0 55 
J 0
(-7436 2650);
DISPLAY 0.638298 (-7436 2650);
PAINT MONO (-7436 2650);
FORCEPROP 2 LAST PATH I244
J 0
(-7325 2700);
DISPLAY 1.021277 (-7325 2700);
DISPLAY INVISIBLE (-7325 2700);
FORCEPROP 1 LAST COMMENT_BODY TRUE
J 0
(-7670 2555);
DISPLAY 0.872340 (-7670 2555);
PAINT PEACH (-7670 2555);
DISPLAY INVISIBLE (-7670 2555);
FORCEPROP 1 LAST OFFPAGE TRUE
J 0
(-7300 2525);
DISPLAY 0.872340 (-7300 2525);
PAINT GREEN (-7300 2525);
DISPLAY INVISIBLE (-7300 2525);
FORCEPROP 2 LAST CDS_LIB standard
J 0
(-7625 2650);
DISPLAY INVISIBLE (-7625 2650);
FORCEADD OFFPAGE..2
(-7625 2600);
FORCEPROP 2 LAST $XR1 136 
J 0
(-7346 2600);
DISPLAY 0.638298 (-7346 2600);
PAINT MONO (-7346 2600);
FORCEPROP 2 LAST $XR0 55 
J 0
(-7436 2600);
DISPLAY 0.638298 (-7436 2600);
PAINT MONO (-7436 2600);
FORCEPROP 2 LAST PATH I245
J 0
(-7325 2650);
DISPLAY 1.021277 (-7325 2650);
DISPLAY INVISIBLE (-7325 2650);
FORCEPROP 1 LAST COMMENT_BODY TRUE
J 0
(-7670 2505);
DISPLAY 0.872340 (-7670 2505);
PAINT PEACH (-7670 2505);
DISPLAY INVISIBLE (-7670 2505);
FORCEPROP 1 LAST OFFPAGE TRUE
J 0
(-7300 2475);
DISPLAY 0.872340 (-7300 2475);
PAINT GREEN (-7300 2475);
DISPLAY INVISIBLE (-7300 2475);
FORCEPROP 2 LAST CDS_LIB standard
J 0
(-7625 2600);
DISPLAY INVISIBLE (-7625 2600);
FORCEADD VCC_CORE..1
(-8525 3225);
FORCEPROP 3 LASTPIN (-8525 3175) SIG_NAME PVDD11_S3_P1\g
J 0
(-8515 3185);
DISPLAY 0.659574 (-8515 3185);
PAINT MONO (-8515 3185);
DISPLAY INVISIBLE (-8515 3185);
FORCEPROP 1 LAST HDL_POWER PVDD11_S3_P1
J 1
(-8525 3275);
DISPLAY 0.489362 (-8525 3275);
PAINT GREEN (-8525 3275);
FORCEPROP 1 LAST PATH I246
J 0
(-8475 3250);
DISPLAY 0.872340 (-8475 3250);
PAINT AQUA (-8475 3250);
DISPLAY INVISIBLE (-8475 3250);
FORCEPROP 2 LAST CDS_LIB pure_quanta_power
J 0
(-8525 3225);
DISPLAY INVISIBLE (-8525 3225);
FORCEADD Q_RES..2
(-8525 2925);
FORCEPROP 1 LAST LOCATION R563
J 0
(-8480 3000);
DISPLAY 0.489362 (-8480 3000);
PAINT SKYBLUE (-8480 3000);
FORCEPROP 0 LAST $SEC 1
J 0
(-8475 3075);
DISPLAY 0.680851 (-8475 3075);
PAINT MONO (-8475 3075);
DISPLAY INVISIBLE (-8475 3075);
FORCEPROP 0 LAST CDS_SEC 1
J 0
(-8475 3075);
DISPLAY 1.021277 (-8475 3075);
DISPLAY INVISIBLE (-8475 3075);
FORCEPROP 1 LASTPIN (-8525 3025) $PN 1
J 0
(-8520 2987);
DISPLAY 0.489362 (-8520 2987);
PAINT MONO (-8520 2987);
FORCEPROP 1 LASTPIN (-8525 2825) $PN 2
J 0
(-8520 2835);
DISPLAY 0.489362 (-8520 2835);
PAINT MONO (-8520 2835);
FORCEPROP 1 LAST MATERIAL EMPTY
J 0
(-8475 2900);
DISPLAY 0.489362 (-8475 2900);
PAINT RED (-8475 2900);
FORCEPROP 1 LAST TOLERANCE 5%
J 0
(-8475 2950);
DISPLAY 0.489362 (-8475 2950);
PAINT SKYBLUE (-8475 2950);
FORCEPROP 1 LAST VALUE 1K
J 0
(-8475 2975);
DISPLAY 0.489362 (-8475 2975);
PAINT SKYBLUE (-8475 2975);
FORCEPROP 1 LAST PART_NUMBER TMP_QCS21002JB34
J 0
(-8475 2850);
DISPLAY 0.489362 (-8475 2850);
PAINT SKYBLUE (-8475 2850);
DISPLAY INVISIBLE (-8475 2850);
FORCEPROP 1 LAST PATH I247
J 0
(-8475 3100);
DISPLAY 0.978723 (-8475 3100);
PAINT WHITE (-8475 3100);
DISPLAY INVISIBLE (-8475 3100);
FORCEPROP 2 LAST CDS_LIB pure_quanta
J 0
(-8525 2925);
DISPLAY INVISIBLE (-8525 2925);
FORCEPROP 1 LAST WATTAGE 1/16W
J 0
(-8475 2925);
DISPLAY 0.489362 (-8475 2925);
PAINT SKYBLUE (-8475 2925);
DISPLAY INVISIBLE (-8475 2925);
FORCEPROP 1 LAST PACK_TYPE 0402LF
J 0
(-8475 2875);
DISPLAY 0.489362 (-8475 2875);
PAINT SKYBLUE (-8475 2875);
DISPLAY INVISIBLE (-8475 2875);
FORCEADD Q_RES..2
(-8700 2925);
FORCEPROP 1 LAST LOCATION R543
J 0
(-8655 3000);
DISPLAY 0.489362 (-8655 3000);
PAINT SKYBLUE (-8655 3000);
FORCEPROP 0 LAST $SEC 1
J 0
(-8650 3075);
DISPLAY 0.680851 (-8650 3075);
PAINT MONO (-8650 3075);
DISPLAY INVISIBLE (-8650 3075);
FORCEPROP 0 LAST CDS_SEC 1
J 0
(-8650 3075);
DISPLAY 1.021277 (-8650 3075);
DISPLAY INVISIBLE (-8650 3075);
FORCEPROP 1 LASTPIN (-8700 3025) $PN 1
J 0
(-8695 2987);
DISPLAY 0.489362 (-8695 2987);
PAINT MONO (-8695 2987);
FORCEPROP 1 LASTPIN (-8700 2825) $PN 2
J 0
(-8695 2835);
DISPLAY 0.489362 (-8695 2835);
PAINT MONO (-8695 2835);
FORCEPROP 1 LAST TOLERANCE 5%
J 0
(-8650 2950);
DISPLAY 0.489362 (-8650 2950);
PAINT SKYBLUE (-8650 2950);
FORCEPROP 1 LAST VALUE 1K
J 0
(-8650 2975);
DISPLAY 0.489362 (-8650 2975);
PAINT SKYBLUE (-8650 2975);
FORCEPROP 1 LAST MATERIAL EMPTY
J 0
(-8650 2900);
DISPLAY 0.489362 (-8650 2900);
PAINT RED (-8650 2900);
FORCEPROP 1 LAST PART_NUMBER TMP_QCS21002JB34
J 0
(-8650 2850);
DISPLAY 0.489362 (-8650 2850);
PAINT SKYBLUE (-8650 2850);
DISPLAY INVISIBLE (-8650 2850);
FORCEPROP 1 LAST PACK_TYPE 0402LF
J 0
(-8650 2875);
DISPLAY 0.489362 (-8650 2875);
PAINT SKYBLUE (-8650 2875);
DISPLAY INVISIBLE (-8650 2875);
FORCEPROP 1 LAST WATTAGE 1/16W
J 0
(-8650 2925);
DISPLAY 0.489362 (-8650 2925);
PAINT SKYBLUE (-8650 2925);
DISPLAY INVISIBLE (-8650 2925);
FORCEPROP 1 LAST PATH I248
J 0
(-8650 3100);
DISPLAY 0.978723 (-8650 3100);
PAINT WHITE (-8650 3100);
DISPLAY INVISIBLE (-8650 3100);
FORCEPROP 2 LAST CDS_LIB pure_quanta
J 0
(-8700 2925);
DISPLAY INVISIBLE (-8700 2925);
FORCEADD Q_RES..2
(-8875 2925);
FORCEPROP 1 LAST LOCATION R542
J 0
(-8825 3000);
DISPLAY 0.489362 (-8825 3000);
PAINT SKYBLUE (-8825 3000);
FORCEPROP 0 LAST $SEC 1
J 2
(-8825 3050);
DISPLAY 0.680851 (-8825 3050);
PAINT MONO (-8825 3050);
DISPLAY INVISIBLE (-8825 3050);
FORCEPROP 0 LAST CDS_SEC 1
J 2
(-8825 3050);
DISPLAY 1.021277 (-8825 3050);
DISPLAY INVISIBLE (-8825 3050);
FORCEPROP 1 LASTPIN (-8875 3025) $PN 1
J 0
(-8870 2987);
DISPLAY 0.489362 (-8870 2987);
PAINT MONO (-8870 2987);
FORCEPROP 1 LASTPIN (-8875 2825) $PN 2
J 0
(-8870 2835);
DISPLAY 0.489362 (-8870 2835);
PAINT MONO (-8870 2835);
FORCEPROP 1 LAST MATERIAL EMPTY
J 0
(-8825 2900);
DISPLAY 0.489362 (-8825 2900);
PAINT RED (-8825 2900);
FORCEPROP 1 LAST TOLERANCE 5%
J 0
(-8825 2950);
DISPLAY 0.489362 (-8825 2950);
PAINT SKYBLUE (-8825 2950);
FORCEPROP 1 LAST VALUE 1K
J 0
(-8825 2975);
DISPLAY 0.489362 (-8825 2975);
PAINT SKYBLUE (-8825 2975);
FORCEPROP 1 LAST PART_NUMBER TMP_QCS21002JB34
J 0
(-8825 2850);
DISPLAY 0.489362 (-8825 2850);
PAINT SKYBLUE (-8825 2850);
DISPLAY INVISIBLE (-8825 2850);
FORCEPROP 1 LAST PACK_TYPE 0402LF
J 0
(-8825 2875);
DISPLAY 0.489362 (-8825 2875);
PAINT SKYBLUE (-8825 2875);
DISPLAY INVISIBLE (-8825 2875);
FORCEPROP 1 LAST WATTAGE 1/16W
J 0
(-8825 2925);
DISPLAY 0.489362 (-8825 2925);
PAINT SKYBLUE (-8825 2925);
DISPLAY INVISIBLE (-8825 2925);
FORCEPROP 1 LAST PATH I249
J 0
(-8825 3100);
DISPLAY 0.978723 (-8825 3100);
PAINT WHITE (-8825 3100);
DISPLAY INVISIBLE (-8825 3100);
FORCEPROP 2 LAST CDS_LIB pure_quanta
J 2
(-8875 2925);
DISPLAY INVISIBLE (-8875 2925);
FORCEADD Q_RES..2
(-9050 2925);
FORCEPROP 1 LAST LOCATION R541
J 0
(-9000 3000);
DISPLAY 0.489362 (-9000 3000);
PAINT SKYBLUE (-9000 3000);
FORCEPROP 0 LAST $SEC 1
J 2
(-9000 3050);
DISPLAY 0.680851 (-9000 3050);
PAINT MONO (-9000 3050);
DISPLAY INVISIBLE (-9000 3050);
FORCEPROP 0 LAST CDS_SEC 1
J 2
(-9000 3050);
DISPLAY 1.021277 (-9000 3050);
DISPLAY INVISIBLE (-9000 3050);
FORCEPROP 1 LASTPIN (-9050 3025) $PN 1
J 0
(-9045 2987);
DISPLAY 0.489362 (-9045 2987);
PAINT MONO (-9045 2987);
FORCEPROP 1 LASTPIN (-9050 2825) $PN 2
J 0
(-9045 2835);
DISPLAY 0.489362 (-9045 2835);
PAINT MONO (-9045 2835);
FORCEPROP 1 LAST MATERIAL EMPTY
J 0
(-9000 2900);
DISPLAY 0.489362 (-9000 2900);
PAINT RED (-9000 2900);
FORCEPROP 1 LAST TOLERANCE 5%
J 0
(-9000 2950);
DISPLAY 0.489362 (-9000 2950);
PAINT SKYBLUE (-9000 2950);
FORCEPROP 1 LAST VALUE 1K
J 0
(-9000 2975);
DISPLAY 0.489362 (-9000 2975);
PAINT SKYBLUE (-9000 2975);
FORCEPROP 1 LAST PART_NUMBER TMP_QCS21002JB34
J 0
(-9000 2850);
DISPLAY 0.489362 (-9000 2850);
PAINT SKYBLUE (-9000 2850);
DISPLAY INVISIBLE (-9000 2850);
FORCEPROP 1 LAST PACK_TYPE 0402LF
J 0
(-9000 2875);
DISPLAY 0.489362 (-9000 2875);
PAINT SKYBLUE (-9000 2875);
DISPLAY INVISIBLE (-9000 2875);
FORCEPROP 1 LAST WATTAGE 1/16W
J 0
(-9000 2925);
DISPLAY 0.489362 (-9000 2925);
PAINT SKYBLUE (-9000 2925);
DISPLAY INVISIBLE (-9000 2925);
FORCEPROP 1 LAST PATH I250
J 0
(-9000 3100);
DISPLAY 0.978723 (-9000 3100);
PAINT WHITE (-9000 3100);
DISPLAY INVISIBLE (-9000 3100);
FORCEPROP 2 LAST CDS_LIB pure_quanta
J 2
(-9050 2925);
DISPLAY INVISIBLE (-9050 2925);
FORCEADD OFFPAGE..2
R 2
(-6850 4425);
FORCEPROP 2 LAST $XR1 136 
J 0
(-7224 4425);
DISPLAY 0.638298 (-7224 4425);
PAINT MONO (-7224 4425);
FORCEPROP 2 LAST $XR0 55 
J 0
(-7104 4425);
DISPLAY 0.638298 (-7104 4425);
PAINT MONO (-7104 4425);
FORCEPROP 2 LAST PATH I251
J 0
(-7100 4475);
DISPLAY 1.021277 (-7100 4475);
DISPLAY INVISIBLE (-7100 4475);
FORCEPROP 1 LAST COMMENT_BODY TRUE
J 2
(-6805 4330);
DISPLAY 0.872340 (-6805 4330);
PAINT GREEN (-6805 4330);
DISPLAY INVISIBLE (-6805 4330);
FORCEPROP 1 LAST OFFPAGE TRUE
J 2
(-7175 4300);
DISPLAY 0.872340 (-7175 4300);
PAINT GREEN (-7175 4300);
DISPLAY INVISIBLE (-7175 4300);
FORCEPROP 2 LAST CDS_LIB standard
J 2
(-6850 4425);
DISPLAY INVISIBLE (-6850 4425);
FORCEADD OFFPAGE..3
R 2
(-6850 4375);
FORCEPROP 2 LAST $XR1 136 
J 0
(-7219 4375);
DISPLAY 0.638298 (-7219 4375);
PAINT MONO (-7219 4375);
FORCEPROP 2 LAST $XR0 55 
J 0
(-7099 4375);
DISPLAY 0.638298 (-7099 4375);
PAINT MONO (-7099 4375);
FORCEPROP 2 LAST PATH I252
J 0
(-7125 4425);
DISPLAY 1.021277 (-7125 4425);
DISPLAY INVISIBLE (-7125 4425);
FORCEPROP 1 LAST COMMENT_BODY TRUE
J 2
(-6800 4275);
DISPLAY 0.872340 (-6800 4275);
PAINT PEACH (-6800 4275);
DISPLAY INVISIBLE (-6800 4275);
FORCEPROP 1 LAST OFFPAGE TRUE
J 2
(-7175 4250);
DISPLAY 0.872340 (-7175 4250);
PAINT GREEN (-7175 4250);
DISPLAY INVISIBLE (-7175 4250);
FORCEPROP 2 LAST CDS_LIB standard
J 0
(-6850 4375);
DISPLAY INVISIBLE (-6850 4375);
FORCEADD OFFPAGE..2
R 2
(-6850 4325);
FORCEPROP 2 LAST $XR1 136 
J 0
(-7224 4325);
DISPLAY 0.638298 (-7224 4325);
PAINT MONO (-7224 4325);
FORCEPROP 2 LAST $XR0 55 
J 0
(-7104 4325);
DISPLAY 0.638298 (-7104 4325);
PAINT MONO (-7104 4325);
FORCEPROP 2 LAST PATH I253
J 0
(-7100 4375);
DISPLAY 1.021277 (-7100 4375);
DISPLAY INVISIBLE (-7100 4375);
FORCEPROP 1 LAST COMMENT_BODY TRUE
J 2
(-6805 4230);
DISPLAY 0.872340 (-6805 4230);
PAINT GREEN (-6805 4230);
DISPLAY INVISIBLE (-6805 4230);
FORCEPROP 1 LAST OFFPAGE TRUE
J 2
(-7175 4200);
DISPLAY 0.872340 (-7175 4200);
PAINT GREEN (-7175 4200);
DISPLAY INVISIBLE (-7175 4200);
FORCEPROP 2 LAST CDS_LIB standard
J 2
(-6850 4325);
DISPLAY INVISIBLE (-6850 4325);
FORCEADD OFFPAGE..3
R 2
(-6850 4275);
FORCEPROP 2 LAST $XR1 136 
J 0
(-7219 4275);
DISPLAY 0.638298 (-7219 4275);
PAINT MONO (-7219 4275);
FORCEPROP 2 LAST $XR0 55 
J 0
(-7099 4275);
DISPLAY 0.638298 (-7099 4275);
PAINT MONO (-7099 4275);
FORCEPROP 2 LAST PATH I254
J 0
(-7125 4325);
DISPLAY 1.021277 (-7125 4325);
DISPLAY INVISIBLE (-7125 4325);
FORCEPROP 1 LAST COMMENT_BODY TRUE
J 2
(-6800 4175);
DISPLAY 0.872340 (-6800 4175);
PAINT PEACH (-6800 4175);
DISPLAY INVISIBLE (-6800 4175);
FORCEPROP 1 LAST OFFPAGE TRUE
J 2
(-7175 4150);
DISPLAY 0.872340 (-7175 4150);
PAINT GREEN (-7175 4150);
DISPLAY INVISIBLE (-7175 4150);
FORCEPROP 2 LAST CDS_LIB standard
J 0
(-6850 4275);
DISPLAY INVISIBLE (-6850 4275);
FORCEADD OFFPAGE..3
(-2150 3125);
FORCEPROP 2 LAST $XR0 138 
J 0
(-1936 3125);
DISPLAY 0.638298 (-1936 3125);
PAINT MONO (-1936 3125);
FORCEPROP 2 LAST PATH I255
J 0
(-1950 3200);
DISPLAY 1.021277 (-1950 3200);
DISPLAY INVISIBLE (-1950 3200);
FORCEPROP 1 LAST COMMENT_BODY TRUE
J 0
(-2200 3025);
DISPLAY 0.872340 (-2200 3025);
PAINT PEACH (-2200 3025);
DISPLAY INVISIBLE (-2200 3025);
FORCEPROP 1 LAST OFFPAGE TRUE
J 0
(-1825 3000);
DISPLAY 0.872340 (-1825 3000);
PAINT GREEN (-1825 3000);
DISPLAY INVISIBLE (-1825 3000);
FORCEPROP 2 LAST CDS_LIB standard
J 0
(-2150 3125);
DISPLAY INVISIBLE (-2150 3125);
FORCEADD OFFPAGE..1
R 2
(-2150 3175);
FORCEPROP 2 LAST $XR0 138 
J 0
(-1964 3175);
DISPLAY 0.638298 (-1964 3175);
PAINT MONO (-1964 3175);
FORCEPROP 2 LAST PATH I256
J 0
(-1975 3250);
DISPLAY 1.021277 (-1975 3250);
DISPLAY INVISIBLE (-1975 3250);
FORCEPROP 1 LAST COMMENT_BODY TRUE
J 2
(-2275 3075);
DISPLAY 0.872340 (-2275 3075);
PAINT GREEN (-2275 3075);
DISPLAY INVISIBLE (-2275 3075);
FORCEPROP 1 LAST OFFPAGE TRUE
J 2
(-2475 3050);
DISPLAY 0.872340 (-2475 3050);
PAINT GREEN (-2475 3050);
DISPLAY INVISIBLE (-2475 3050);
FORCEPROP 2 LAST CDS_LIB standard
J 0
(-2150 3175);
DISPLAY INVISIBLE (-2150 3175);
FORCEADD OFFPAGE..2
(-7700 550);
FORCEPROP 2 LAST $XR1 80 
J 0
(-7421 550);
DISPLAY 0.638298 (-7421 550);
PAINT MONO (-7421 550);
FORCEPROP 2 LAST $XR0 55 
J 0
(-7511 550);
DISPLAY 0.638298 (-7511 550);
PAINT MONO (-7511 550);
FORCEPROP 2 LAST PATH I257
J 0
(-7400 600);
DISPLAY 1.021277 (-7400 600);
DISPLAY INVISIBLE (-7400 600);
FORCEPROP 1 LAST COMMENT_BODY TRUE
J 0
(-7745 455);
DISPLAY 0.872340 (-7745 455);
PAINT GREEN (-7745 455);
DISPLAY INVISIBLE (-7745 455);
FORCEPROP 1 LAST OFFPAGE TRUE
J 0
(-7375 425);
DISPLAY 0.872340 (-7375 425);
PAINT GREEN (-7375 425);
DISPLAY INVISIBLE (-7375 425);
FORCEPROP 2 LAST CDS_LIB standard
J 0
(-7700 550);
DISPLAY INVISIBLE (-7700 550);
FORCEADD Q_RES..1
R 1
(-8525 1100);
FORCEPROP 1 LAST LOCATION R583
J 0
(-8500 1000);
DISPLAY 0.489362 (-8500 1000);
PAINT SKYBLUE (-8500 1000);
FORCEPROP 0 LAST $SEC 1
R 1
J 0
(-8500 1150);
DISPLAY 0.680851 (-8500 1150);
PAINT MONO (-8500 1150);
DISPLAY INVISIBLE (-8500 1150);
FORCEPROP 0 LAST CDS_SEC 1
R 1
J 0
(-8500 1150);
DISPLAY 1.021277 (-8500 1150);
DISPLAY INVISIBLE (-8500 1150);
FORCEPROP 1 LASTPIN (-8525 1000) $PN 1
R 1
J 0
(-8535 1010);
DISPLAY 0.489362 (-8535 1010);
PAINT MONO (-8535 1010);
FORCEPROP 1 LASTPIN (-8525 1200) $PN 2
R 1
J 0
(-8537 1162);
DISPLAY 0.489362 (-8537 1162);
PAINT MONO (-8537 1162);
FORCEPROP 1 LAST VALUE 4.7K
J 0
(-8500 1075);
DISPLAY 0.489362 (-8500 1075);
PAINT SKYBLUE (-8500 1075);
FORCEPROP 1 LAST MATERIAL EMPTY
J 0
(-8500 1125);
DISPLAY 0.489362 (-8500 1125);
PAINT RED (-8500 1125);
FORCEPROP 1 LAST PACK_TYPE 0402LF
R 1
J 0
(-8375 1350);
DISPLAY 0.978723 (-8375 1350);
PAINT SKYBLUE (-8375 1350);
DISPLAY INVISIBLE (-8375 1350);
FORCEPROP 1 LAST PART_NUMBER TMP_QCS24702JB38
R 1
J 0
(-8625 1050);
DISPLAY 0.978723 (-8625 1050);
PAINT SKYBLUE (-8625 1050);
DISPLAY INVISIBLE (-8625 1050);
FORCEPROP 1 LAST TOLERANCE 5%
R 1
J 0
(-8425 1100);
DISPLAY 0.978723 (-8425 1100);
PAINT SKYBLUE (-8425 1100);
DISPLAY INVISIBLE (-8425 1100);
FORCEPROP 1 LAST WATTAGE 1/16W
R 1
J 2
(-8375 1075);
DISPLAY 0.978723 (-8375 1075);
PAINT SKYBLUE (-8375 1075);
DISPLAY INVISIBLE (-8375 1075);
FORCEPROP 1 LAST PATH I258
R 1
J 0
(-8675 1050);
DISPLAY 0.978723 (-8675 1050);
PAINT WHITE (-8675 1050);
DISPLAY INVISIBLE (-8675 1050);
FORCEPROP 2 LAST CDS_LIB pure_quanta
J 0
(-8525 1100);
DISPLAY INVISIBLE (-8525 1100);
FORCEADD Q_RES..1
(-2250 2425);
FORCEPROP 1 LAST LOCATION R573
J 0
(-2425 2425);
DISPLAY 0.489362 (-2425 2425);
PAINT SKYBLUE (-2425 2425);
FORCEPROP 0 LAST $SEC 1
J 0
(-1975 2475);
DISPLAY 0.680851 (-1975 2475);
PAINT MONO (-1975 2475);
DISPLAY INVISIBLE (-1975 2475);
FORCEPROP 0 LAST CDS_SEC 1
J 0
(-1975 2475);
DISPLAY 1.021277 (-1975 2475);
DISPLAY INVISIBLE (-1975 2475);
FORCEPROP 1 LASTPIN (-2350 2425) $PN 1
J 0
(-2338 2437);
DISPLAY 0.489362 (-2338 2437);
PAINT MONO (-2338 2437);
FORCEPROP 1 LASTPIN (-2150 2425) $PN 2
J 0
(-2188 2437);
DISPLAY 0.489362 (-2188 2437);
PAINT MONO (-2188 2437);
FORCEPROP 1 LAST VALUE 0
J 2
(-2050 2425);
DISPLAY 0.489362 (-2050 2425);
PAINT SKYBLUE (-2050 2425);
FORCEPROP 1 LAST MATERIAL CHIP
J 0
(-2425 2400);
DISPLAY 0.489362 (-2425 2400);
PAINT SKYBLUE (-2425 2400);
FORCEPROP 1 LAST PACK_TYPE 0402LF
J 0
(-2000 2275);
DISPLAY 0.978723 (-2000 2275);
PAINT SKYBLUE (-2000 2275);
DISPLAY INVISIBLE (-2000 2275);
FORCEPROP 1 LAST PART_NUMBER CS00002JB38
J 0
(-2300 2550);
DISPLAY 0.978723 (-2300 2550);
PAINT SKYBLUE (-2300 2550);
DISPLAY INVISIBLE (-2300 2550);
FORCEPROP 1 LAST TOLERANCE 5%
J 0
(-2250 2325);
DISPLAY 0.978723 (-2250 2325);
PAINT SKYBLUE (-2250 2325);
DISPLAY INVISIBLE (-2250 2325);
FORCEPROP 1 LAST WATTAGE 1/16W
J 2
(-2275 2275);
DISPLAY 0.978723 (-2275 2275);
PAINT SKYBLUE (-2275 2275);
DISPLAY INVISIBLE (-2275 2275);
FORCEPROP 1 LAST PATH I26
J 0
(-2300 2575);
DISPLAY 0.978723 (-2300 2575);
PAINT WHITE (-2300 2575);
DISPLAY INVISIBLE (-2300 2575);
FORCEPROP 2 LAST CDS_LIB pure_quanta
J 0
(-2250 2425);
DISPLAY INVISIBLE (-2250 2425);
FORCEADD UNIVERSAL_GND..1
(-8525 225);
FORCEPROP 3 LASTPIN (-8525 275) SIG_NAME GND\g
J 0
(-8515 285);
DISPLAY 0.659574 (-8515 285);
PAINT MONO (-8515 285);
DISPLAY INVISIBLE (-8515 285);
FORCEPROP 1 LAST HDL_POWER GND
J 1
(-8500 150);
DISPLAY 0.872340 (-8500 150);
PAINT GREEN (-8500 150);
DISPLAY INVISIBLE (-8500 150);
FORCEPROP 1 LAST PATH I260
J 0
(-8450 225);
DISPLAY 0.872340 (-8450 225);
PAINT AQUA (-8450 225);
DISPLAY INVISIBLE (-8450 225);
FORCEPROP 2 LAST CDS_LIB pure_quanta_power
J 0
(-8525 225);
DISPLAY INVISIBLE (-8525 225);
FORCEADD Q_RES..1
R 1
(-8525 375);
FORCEPROP 1 LAST LOCATION R584
J 0
(-8500 275);
DISPLAY 0.489362 (-8500 275);
PAINT SKYBLUE (-8500 275);
FORCEPROP 0 LAST $SEC 1
R 1
J 0
(-8500 425);
DISPLAY 0.680851 (-8500 425);
PAINT MONO (-8500 425);
DISPLAY INVISIBLE (-8500 425);
FORCEPROP 0 LAST CDS_SEC 1
R 1
J 0
(-8500 425);
DISPLAY 1.021277 (-8500 425);
DISPLAY INVISIBLE (-8500 425);
FORCEPROP 1 LASTPIN (-8525 275) $PN 1
R 1
J 0
(-8537 287);
DISPLAY 0.489362 (-8537 287);
PAINT MONO (-8537 287);
FORCEPROP 1 LASTPIN (-8525 475) $PN 2
R 1
J 0
(-8537 437);
DISPLAY 0.489362 (-8537 437);
PAINT MONO (-8537 437);
FORCEPROP 1 LAST MATERIAL EMPTY
J 0
(-8500 400);
DISPLAY 0.489362 (-8500 400);
PAINT RED (-8500 400);
FORCEPROP 1 LAST VALUE 4.7K
J 0
(-8500 350);
DISPLAY 0.489362 (-8500 350);
PAINT SKYBLUE (-8500 350);
FORCEPROP 1 LAST PACK_TYPE 0402LF
R 1
J 0
(-8375 625);
DISPLAY 0.978723 (-8375 625);
PAINT SKYBLUE (-8375 625);
DISPLAY INVISIBLE (-8375 625);
FORCEPROP 1 LAST PART_NUMBER TMP_QCS24702JB38
R 1
J 0
(-8625 325);
DISPLAY 0.978723 (-8625 325);
PAINT SKYBLUE (-8625 325);
DISPLAY INVISIBLE (-8625 325);
FORCEPROP 1 LAST TOLERANCE 5%
R 1
J 0
(-8425 375);
DISPLAY 0.978723 (-8425 375);
PAINT SKYBLUE (-8425 375);
DISPLAY INVISIBLE (-8425 375);
FORCEPROP 1 LAST WATTAGE 1/16W
R 1
J 2
(-8375 350);
DISPLAY 0.978723 (-8375 350);
PAINT SKYBLUE (-8375 350);
DISPLAY INVISIBLE (-8375 350);
FORCEPROP 1 LAST PATH I261
R 1
J 0
(-8675 325);
DISPLAY 0.978723 (-8675 325);
PAINT WHITE (-8675 325);
DISPLAY INVISIBLE (-8675 325);
FORCEPROP 2 LAST CDS_LIB pure_quanta
J 0
(-8525 375);
DISPLAY INVISIBLE (-8525 375);
FORCEADD UNIVERSAL_GND..1
(-8750 225);
FORCEPROP 3 LASTPIN (-8750 275) SIG_NAME GND\g
J 0
(-8740 285);
DISPLAY 0.659574 (-8740 285);
PAINT MONO (-8740 285);
DISPLAY INVISIBLE (-8740 285);
FORCEPROP 1 LAST HDL_POWER GND
J 1
(-8725 150);
DISPLAY 0.872340 (-8725 150);
PAINT GREEN (-8725 150);
DISPLAY INVISIBLE (-8725 150);
FORCEPROP 1 LAST PATH I263
J 0
(-8675 225);
DISPLAY 0.872340 (-8675 225);
PAINT AQUA (-8675 225);
DISPLAY INVISIBLE (-8675 225);
FORCEPROP 2 LAST CDS_LIB pure_quanta_power
J 0
(-8750 225);
DISPLAY INVISIBLE (-8750 225);
FORCEADD UNIVERSAL_POWER..1
(-8750 1300);
FORCEPROP 3 LASTPIN (-8750 1250) SIG_NAME PVDD18_S5_P1\g
J 0
(-8740 1260);
DISPLAY 0.659574 (-8740 1260);
PAINT MONO (-8740 1260);
DISPLAY INVISIBLE (-8740 1260);
FORCEPROP 1 LAST HDL_POWER PVDD18_S5_P1
J 1
(-8750 1350);
DISPLAY 0.489362 (-8750 1350);
PAINT GREEN (-8750 1350);
FORCEPROP 1 LAST PATH I264
J 0
(-8700 1325);
DISPLAY 0.872340 (-8700 1325);
PAINT AQUA (-8700 1325);
DISPLAY INVISIBLE (-8700 1325);
FORCEPROP 2 LAST CDS_LIB pure_quanta_power
J 0
(-8750 1300);
DISPLAY INVISIBLE (-8750 1300);
FORCEADD Q_RES..1
R 1
(-8750 1100);
FORCEPROP 1 LAST LOCATION R456
J 0
(-8725 1025);
DISPLAY 0.489362 (-8725 1025);
PAINT SKYBLUE (-8725 1025);
FORCEPROP 2 LAST $SEC 1
J 0
(-8725 1150);
DISPLAY 0.680851 (-8725 1150);
PAINT MONO (-8725 1150);
DISPLAY INVISIBLE (-8725 1150);
FORCEPROP 2 LAST CDS_SEC 1
J 0
(-8725 1150);
DISPLAY 1.021277 (-8725 1150);
DISPLAY INVISIBLE (-8725 1150);
FORCEPROP 1 LASTPIN (-8750 1000) $PN 1
R 1
J 0
(-8762 1012);
DISPLAY 0.489362 (-8762 1012);
PAINT MONO (-8762 1012);
FORCEPROP 1 LASTPIN (-8750 1200) $PN 2
R 1
J 0
(-8762 1162);
DISPLAY 0.489362 (-8762 1162);
PAINT MONO (-8762 1162);
FORCEPROP 1 LAST VALUE 4.7K
J 0
(-8725 1075);
DISPLAY 0.489362 (-8725 1075);
PAINT SKYBLUE (-8725 1075);
FORCEPROP 1 LAST MATERIAL EMPTY
J 0
(-8725 1125);
DISPLAY 0.489362 (-8725 1125);
PAINT RED (-8725 1125);
FORCEPROP 1 LAST PACK_TYPE 0402LF
R 1
J 0
(-8600 1350);
DISPLAY 0.978723 (-8600 1350);
PAINT SKYBLUE (-8600 1350);
DISPLAY INVISIBLE (-8600 1350);
FORCEPROP 1 LAST PART_NUMBER TMP_QCS24702JB38
R 1
J 0
(-8850 1050);
DISPLAY 0.978723 (-8850 1050);
PAINT SKYBLUE (-8850 1050);
DISPLAY INVISIBLE (-8850 1050);
FORCEPROP 1 LAST TOLERANCE 5%
R 1
J 0
(-8650 1100);
DISPLAY 0.978723 (-8650 1100);
PAINT SKYBLUE (-8650 1100);
DISPLAY INVISIBLE (-8650 1100);
FORCEPROP 1 LAST WATTAGE 1/16W
R 1
J 2
(-8600 1075);
DISPLAY 0.978723 (-8600 1075);
PAINT SKYBLUE (-8600 1075);
DISPLAY INVISIBLE (-8600 1075);
FORCEPROP 1 LAST PATH I265
R 1
J 0
(-8900 1050);
DISPLAY 0.978723 (-8900 1050);
PAINT WHITE (-8900 1050);
DISPLAY INVISIBLE (-8900 1050);
FORCEPROP 2 LAST CDS_LIB pure_quanta
J 0
(-8750 1100);
DISPLAY INVISIBLE (-8750 1100);
FORCEADD Q_RES..1
R 1
(-8750 375);
FORCEPROP 1 LAST LOCATION R491
J 0
(-8725 300);
DISPLAY 0.489362 (-8725 300);
PAINT SKYBLUE (-8725 300);
FORCEPROP 2 LAST $SEC 1
J 0
(-8725 425);
DISPLAY 0.680851 (-8725 425);
PAINT MONO (-8725 425);
DISPLAY INVISIBLE (-8725 425);
FORCEPROP 2 LAST CDS_SEC 1
J 0
(-8725 425);
DISPLAY 1.021277 (-8725 425);
DISPLAY INVISIBLE (-8725 425);
FORCEPROP 1 LASTPIN (-8750 275) $PN 1
R 1
J 0
(-8762 287);
DISPLAY 0.489362 (-8762 287);
PAINT MONO (-8762 287);
FORCEPROP 1 LASTPIN (-8750 475) $PN 2
R 1
J 0
(-8762 437);
DISPLAY 0.489362 (-8762 437);
PAINT MONO (-8762 437);
FORCEPROP 1 LAST VALUE 4.7K
J 0
(-8725 350);
DISPLAY 0.489362 (-8725 350);
PAINT SKYBLUE (-8725 350);
FORCEPROP 1 LAST MATERIAL EMPTY
J 0
(-8725 400);
DISPLAY 0.489362 (-8725 400);
PAINT RED (-8725 400);
FORCEPROP 1 LAST PACK_TYPE 0402LF
R 1
J 0
(-8600 625);
DISPLAY 0.978723 (-8600 625);
PAINT SKYBLUE (-8600 625);
DISPLAY INVISIBLE (-8600 625);
FORCEPROP 1 LAST PART_NUMBER TMP_QCS24702JB38
R 1
J 0
(-8850 325);
DISPLAY 0.978723 (-8850 325);
PAINT SKYBLUE (-8850 325);
DISPLAY INVISIBLE (-8850 325);
FORCEPROP 1 LAST TOLERANCE 5%
R 1
J 0
(-8650 375);
DISPLAY 0.978723 (-8650 375);
PAINT SKYBLUE (-8650 375);
DISPLAY INVISIBLE (-8650 375);
FORCEPROP 1 LAST WATTAGE 1/16W
R 1
J 2
(-8600 350);
DISPLAY 0.978723 (-8600 350);
PAINT SKYBLUE (-8600 350);
DISPLAY INVISIBLE (-8600 350);
FORCEPROP 1 LAST PATH I266
R 1
J 0
(-8900 325);
DISPLAY 0.978723 (-8900 325);
PAINT WHITE (-8900 325);
DISPLAY INVISIBLE (-8900 325);
FORCEPROP 2 LAST CDS_LIB pure_quanta
J 0
(-8750 375);
DISPLAY INVISIBLE (-8750 375);
FORCEADD OFFPAGE..2
(-7700 625);
FORCEPROP 2 LAST $XR1 80 
J 0
(-7421 625);
DISPLAY 0.638298 (-7421 625);
PAINT MONO (-7421 625);
FORCEPROP 2 LAST $XR0 55 
J 0
(-7511 625);
DISPLAY 0.638298 (-7511 625);
PAINT MONO (-7511 625);
FORCEPROP 2 LAST PATH I267
J 0
(-7325 675);
DISPLAY 1.021277 (-7325 675);
DISPLAY INVISIBLE (-7325 675);
FORCEPROP 1 LAST COMMENT_BODY TRUE
J 0
(-7745 530);
DISPLAY 0.872340 (-7745 530);
PAINT GREEN (-7745 530);
DISPLAY INVISIBLE (-7745 530);
FORCEPROP 1 LAST OFFPAGE TRUE
J 0
(-7375 500);
DISPLAY 0.872340 (-7375 500);
PAINT GREEN (-7375 500);
DISPLAY INVISIBLE (-7375 500);
FORCEPROP 2 LAST CDS_LIB standard
J 2
(-7700 625);
DISPLAY INVISIBLE (-7700 625);
FORCEADD OFFPAGE..4
R 2
(-6700 3175);
FORCEPROP 2 LAST $XR0 61 
J 0
(-6951 3175);
DISPLAY 0.638298 (-6951 3175);
PAINT MONO (-6951 3175);
FORCEPROP 2 LAST PATH I268
J 0
(-6650 3250);
DISPLAY 0.680851 (-6650 3250);
DISPLAY INVISIBLE (-6650 3250);
FORCEPROP 1 LAST COMMENT_BODY TRUE
J 2
(-6675 3075);
DISPLAY 0.872340 (-6675 3075);
PAINT GREEN (-6675 3075);
DISPLAY INVISIBLE (-6675 3075);
FORCEPROP 1 LAST OFFPAGE TRUE
J 2
(-7025 3050);
DISPLAY 0.872340 (-7025 3050);
PAINT GREEN (-7025 3050);
DISPLAY INVISIBLE (-7025 3050);
FORCEPROP 2 LAST CDS_LIB standard
J 0
(-6700 3175);
DISPLAY INVISIBLE (-6700 3175);
FORCEADD OFFPAGE..4
R 2
(-6700 3125);
FORCEPROP 2 LAST $XR0 61 
J 0
(-6951 3125);
DISPLAY 0.638298 (-6951 3125);
PAINT MONO (-6951 3125);
FORCEPROP 2 LAST PATH I269
J 0
(-6650 3200);
DISPLAY 0.680851 (-6650 3200);
DISPLAY INVISIBLE (-6650 3200);
FORCEPROP 1 LAST COMMENT_BODY TRUE
J 2
(-6675 3025);
DISPLAY 0.872340 (-6675 3025);
PAINT GREEN (-6675 3025);
DISPLAY INVISIBLE (-6675 3025);
FORCEPROP 1 LAST OFFPAGE TRUE
J 2
(-7025 3000);
DISPLAY 0.872340 (-7025 3000);
PAINT GREEN (-7025 3000);
DISPLAY INVISIBLE (-7025 3000);
FORCEPROP 2 LAST CDS_LIB standard
J 0
(-6700 3125);
DISPLAY INVISIBLE (-6700 3125);
FORCEADD OFFPAGE..1
(-3125 2425);
FORCEPROP 2 LAST $XR1 75 
J 0
(-3436 2425);
DISPLAY 0.638298 (-3436 2425);
PAINT MONO (-3436 2425);
FORCEPROP 2 LAST $XR0 28 
J 0
(-3346 2425);
DISPLAY 0.638298 (-3346 2425);
PAINT MONO (-3346 2425);
FORCEPROP 2 LAST PATH I27
J 0
(-3075 2500);
DISPLAY 1.021277 (-3075 2500);
DISPLAY INVISIBLE (-3075 2500);
FORCEPROP 1 LAST COMMENT_BODY TRUE
J 0
(-3000 2325);
DISPLAY 0.872340 (-3000 2325);
PAINT GREEN (-3000 2325);
DISPLAY INVISIBLE (-3000 2325);
FORCEPROP 1 LAST OFFPAGE TRUE
J 0
(-2800 2300);
DISPLAY 0.872340 (-2800 2300);
PAINT GREEN (-2800 2300);
DISPLAY INVISIBLE (-2800 2300);
FORCEPROP 2 LAST CDS_LIB standard
J 0
(-3125 2425);
DISPLAY INVISIBLE (-3125 2425);
FORCEADD OFFPAGE..2
(-1150 4175);
FORCEPROP 2 LAST $XR0 112 
J 0
(-961 4175);
DISPLAY 0.638298 (-961 4175);
PAINT MONO (-961 4175);
FORCEPROP 2 LAST PATH I277
J 0
(-950 4225);
DISPLAY 0.680851 (-950 4225);
DISPLAY INVISIBLE (-950 4225);
FORCEPROP 1 LAST COMMENT_BODY TRUE
J 0
(-1195 4080);
DISPLAY 0.872340 (-1195 4080);
PAINT GREEN (-1195 4080);
DISPLAY INVISIBLE (-1195 4080);
FORCEPROP 1 LAST OFFPAGE TRUE
J 0
(-825 4050);
DISPLAY 0.872340 (-825 4050);
PAINT GREEN (-825 4050);
DISPLAY INVISIBLE (-825 4050);
FORCEPROP 2 LAST CDS_LIB standard
J 0
(-1150 4175);
DISPLAY INVISIBLE (-1150 4175);
FORCEADD OFFPAGE..2
(-1150 4125);
FORCEPROP 2 LAST $XR0 112 
J 0
(-961 4125);
DISPLAY 0.638298 (-961 4125);
PAINT MONO (-961 4125);
FORCEPROP 2 LAST PATH I278
J 0
(-950 4175);
DISPLAY 0.680851 (-950 4175);
DISPLAY INVISIBLE (-950 4175);
FORCEPROP 1 LAST COMMENT_BODY TRUE
J 0
(-1195 4030);
DISPLAY 0.872340 (-1195 4030);
PAINT GREEN (-1195 4030);
DISPLAY INVISIBLE (-1195 4030);
FORCEPROP 1 LAST OFFPAGE TRUE
J 0
(-825 4000);
DISPLAY 0.872340 (-825 4000);
PAINT GREEN (-825 4000);
DISPLAY INVISIBLE (-825 4000);
FORCEPROP 2 LAST CDS_LIB standard
J 0
(-1150 4125);
DISPLAY INVISIBLE (-1150 4125);
FORCEADD OFFPAGE..2
(-1150 3875);
FORCEPROP 2 LAST $XR0 110 
J 0
(-961 3875);
DISPLAY 0.638298 (-961 3875);
PAINT MONO (-961 3875);
FORCEPROP 2 LAST PATH I279
J 0
(-950 3925);
DISPLAY 0.680851 (-950 3925);
DISPLAY INVISIBLE (-950 3925);
FORCEPROP 1 LAST COMMENT_BODY TRUE
J 0
(-1195 3780);
DISPLAY 0.872340 (-1195 3780);
PAINT GREEN (-1195 3780);
DISPLAY INVISIBLE (-1195 3780);
FORCEPROP 1 LAST OFFPAGE TRUE
J 0
(-825 3750);
DISPLAY 0.872340 (-825 3750);
PAINT GREEN (-825 3750);
DISPLAY INVISIBLE (-825 3750);
FORCEPROP 2 LAST CDS_LIB standard
J 0
(-1150 3875);
DISPLAY INVISIBLE (-1150 3875);
FORCEADD OFFPAGE..2
(-1150 3825);
FORCEPROP 2 LAST $XR0 110 
J 0
(-961 3825);
DISPLAY 0.638298 (-961 3825);
PAINT MONO (-961 3825);
FORCEPROP 2 LAST PATH I280
J 0
(-950 3875);
DISPLAY 0.680851 (-950 3875);
DISPLAY INVISIBLE (-950 3875);
FORCEPROP 1 LAST COMMENT_BODY TRUE
J 0
(-1195 3730);
DISPLAY 0.872340 (-1195 3730);
PAINT GREEN (-1195 3730);
DISPLAY INVISIBLE (-1195 3730);
FORCEPROP 1 LAST OFFPAGE TRUE
J 0
(-825 3700);
DISPLAY 0.872340 (-825 3700);
PAINT GREEN (-825 3700);
DISPLAY INVISIBLE (-825 3700);
FORCEPROP 2 LAST CDS_LIB standard
J 0
(-1150 3825);
DISPLAY INVISIBLE (-1150 3825);
FORCEADD OFFPAGE..2
(-1150 3575);
FORCEPROP 2 LAST $XR0 111 
J 0
(-961 3575);
DISPLAY 0.638298 (-961 3575);
PAINT MONO (-961 3575);
FORCEPROP 2 LAST PATH I281
J 0
(-950 3625);
DISPLAY 0.680851 (-950 3625);
DISPLAY INVISIBLE (-950 3625);
FORCEPROP 1 LAST COMMENT_BODY TRUE
J 0
(-1195 3480);
DISPLAY 0.872340 (-1195 3480);
PAINT GREEN (-1195 3480);
DISPLAY INVISIBLE (-1195 3480);
FORCEPROP 1 LAST OFFPAGE TRUE
J 0
(-825 3450);
DISPLAY 0.872340 (-825 3450);
PAINT GREEN (-825 3450);
DISPLAY INVISIBLE (-825 3450);
FORCEPROP 2 LAST CDS_LIB standard
J 0
(-1150 3575);
DISPLAY INVISIBLE (-1150 3575);
FORCEADD OFFPAGE..2
(-1150 3525);
FORCEPROP 2 LAST $XR0 111 
J 0
(-961 3525);
DISPLAY 0.638298 (-961 3525);
PAINT MONO (-961 3525);
FORCEPROP 2 LAST PATH I282
J 0
(-950 3575);
DISPLAY 0.680851 (-950 3575);
DISPLAY INVISIBLE (-950 3575);
FORCEPROP 1 LAST COMMENT_BODY TRUE
J 0
(-1195 3430);
DISPLAY 0.872340 (-1195 3430);
PAINT GREEN (-1195 3430);
DISPLAY INVISIBLE (-1195 3430);
FORCEPROP 1 LAST OFFPAGE TRUE
J 0
(-825 3400);
DISPLAY 0.872340 (-825 3400);
PAINT GREEN (-825 3400);
DISPLAY INVISIBLE (-825 3400);
FORCEPROP 2 LAST CDS_LIB standard
J 0
(-1150 3525);
DISPLAY INVISIBLE (-1150 3525);
FORCEADD Q_RES..1
(-2125 4175);
FORCEPROP 1 LAST LOCATION R1345
J 0
(-2325 4175);
DISPLAY 0.489362 (-2325 4175);
PAINT SKYBLUE (-2325 4175);
FORCEPROP 0 LAST $SEC 1
J 0
(-2275 4225);
DISPLAY 0.680851 (-2275 4225);
PAINT MONO (-2275 4225);
DISPLAY INVISIBLE (-2275 4225);
FORCEPROP 0 LAST CDS_SEC 1
J 0
(-2275 4225);
DISPLAY 0.680851 (-2275 4225);
DISPLAY INVISIBLE (-2275 4225);
FORCEPROP 1 LASTPIN (-2225 4175) $PN 1
J 0
(-2213 4187);
DISPLAY 0.489362 (-2213 4187);
PAINT MONO (-2213 4187);
FORCEPROP 1 LASTPIN (-2025 4175) $PN 2
J 0
(-2063 4187);
DISPLAY 0.489362 (-2063 4187);
PAINT MONO (-2063 4187);
FORCEPROP 1 LAST VALUE 0
J 2
(-1975 4175);
DISPLAY 0.489362 (-1975 4175);
PAINT SKYBLUE (-1975 4175);
FORCEPROP 1 LAST PACK_TYPE 0402LF
J 0
(-2075 4100);
DISPLAY 0.489362 (-2075 4100);
PAINT SKYBLUE (-2075 4100);
DISPLAY INVISIBLE (-2075 4100);
FORCEPROP 1 LAST PART_NUMBER CS00002JB38
J 0
(-2100 4225);
DISPLAY 0.489362 (-2100 4225);
PAINT SKYBLUE (-2100 4225);
DISPLAY INVISIBLE (-2100 4225);
FORCEPROP 1 LAST TOLERANCE 5%
J 0
(-2150 4100);
DISPLAY 0.489362 (-2150 4100);
PAINT SKYBLUE (-2150 4100);
DISPLAY INVISIBLE (-2150 4100);
FORCEPROP 1 LAST MATERIAL CHIP
J 0
(-1700 4100);
DISPLAY 0.489362 (-1700 4100);
PAINT SKYBLUE (-1700 4100);
DISPLAY INVISIBLE (-1700 4100);
FORCEPROP 1 LAST WATTAGE 1/16W
J 2
(-1725 4100);
DISPLAY 0.489362 (-1725 4100);
PAINT SKYBLUE (-1725 4100);
DISPLAY INVISIBLE (-1725 4100);
FORCEPROP 1 LAST PATH I283
J 0
(-2175 4325);
DISPLAY 0.978723 (-2175 4325);
PAINT WHITE (-2175 4325);
DISPLAY INVISIBLE (-2175 4325);
FORCEPROP 2 LAST CDS_LIB pure_quanta
J 0
(-2125 4175);
DISPLAY INVISIBLE (-2125 4175);
FORCEADD Q_RES..1
(-2125 4125);
FORCEPROP 1 LAST LOCATION R1346
J 0
(-2325 4125);
DISPLAY 0.489362 (-2325 4125);
PAINT SKYBLUE (-2325 4125);
FORCEPROP 0 LAST $SEC 1
J 0
(-2275 4175);
DISPLAY 0.680851 (-2275 4175);
PAINT MONO (-2275 4175);
DISPLAY INVISIBLE (-2275 4175);
FORCEPROP 0 LAST CDS_SEC 1
J 0
(-2275 4175);
DISPLAY 0.680851 (-2275 4175);
DISPLAY INVISIBLE (-2275 4175);
FORCEPROP 1 LASTPIN (-2225 4125) $PN 1
J 0
(-2213 4137);
DISPLAY 0.489362 (-2213 4137);
PAINT MONO (-2213 4137);
FORCEPROP 1 LASTPIN (-2025 4125) $PN 2
J 0
(-2063 4137);
DISPLAY 0.489362 (-2063 4137);
PAINT MONO (-2063 4137);
FORCEPROP 1 LAST VALUE 0
J 2
(-1975 4125);
DISPLAY 0.489362 (-1975 4125);
PAINT SKYBLUE (-1975 4125);
FORCEPROP 1 LAST PACK_TYPE 0402LF
J 0
(-2075 4050);
DISPLAY 0.489362 (-2075 4050);
PAINT SKYBLUE (-2075 4050);
DISPLAY INVISIBLE (-2075 4050);
FORCEPROP 1 LAST PART_NUMBER CS00002JB38
J 0
(-2100 4175);
DISPLAY 0.489362 (-2100 4175);
PAINT SKYBLUE (-2100 4175);
DISPLAY INVISIBLE (-2100 4175);
FORCEPROP 1 LAST TOLERANCE 5%
J 0
(-2150 4050);
DISPLAY 0.489362 (-2150 4050);
PAINT SKYBLUE (-2150 4050);
DISPLAY INVISIBLE (-2150 4050);
FORCEPROP 1 LAST MATERIAL CHIP
J 0
(-1700 4050);
DISPLAY 0.489362 (-1700 4050);
PAINT SKYBLUE (-1700 4050);
DISPLAY INVISIBLE (-1700 4050);
FORCEPROP 1 LAST WATTAGE 1/16W
J 2
(-1725 4050);
DISPLAY 0.489362 (-1725 4050);
PAINT SKYBLUE (-1725 4050);
DISPLAY INVISIBLE (-1725 4050);
FORCEPROP 1 LAST PATH I284
J 0
(-2175 4275);
DISPLAY 0.978723 (-2175 4275);
PAINT WHITE (-2175 4275);
DISPLAY INVISIBLE (-2175 4275);
FORCEPROP 2 LAST CDS_LIB pure_quanta
J 0
(-2125 4125);
DISPLAY INVISIBLE (-2125 4125);
FORCEADD Q_RES..1
(-2125 3875);
FORCEPROP 1 LAST LOCATION R1347
J 0
(-2325 3875);
DISPLAY 0.489362 (-2325 3875);
PAINT SKYBLUE (-2325 3875);
FORCEPROP 0 LAST $SEC 1
J 0
(-2275 3925);
DISPLAY 0.680851 (-2275 3925);
PAINT MONO (-2275 3925);
DISPLAY INVISIBLE (-2275 3925);
FORCEPROP 0 LAST CDS_SEC 1
J 0
(-2275 3925);
DISPLAY 0.680851 (-2275 3925);
DISPLAY INVISIBLE (-2275 3925);
FORCEPROP 1 LASTPIN (-2225 3875) $PN 1
J 0
(-2213 3887);
DISPLAY 0.489362 (-2213 3887);
PAINT MONO (-2213 3887);
FORCEPROP 1 LASTPIN (-2025 3875) $PN 2
J 0
(-2063 3887);
DISPLAY 0.489362 (-2063 3887);
PAINT MONO (-2063 3887);
FORCEPROP 1 LAST VALUE 0
J 2
(-1975 3875);
DISPLAY 0.489362 (-1975 3875);
PAINT SKYBLUE (-1975 3875);
FORCEPROP 1 LAST PACK_TYPE 0402LF
J 0
(-2075 3800);
DISPLAY 0.489362 (-2075 3800);
PAINT SKYBLUE (-2075 3800);
DISPLAY INVISIBLE (-2075 3800);
FORCEPROP 1 LAST PART_NUMBER CS00002JB38
J 0
(-2100 3925);
DISPLAY 0.489362 (-2100 3925);
PAINT SKYBLUE (-2100 3925);
DISPLAY INVISIBLE (-2100 3925);
FORCEPROP 1 LAST TOLERANCE 5%
J 0
(-2150 3800);
DISPLAY 0.489362 (-2150 3800);
PAINT SKYBLUE (-2150 3800);
DISPLAY INVISIBLE (-2150 3800);
FORCEPROP 1 LAST MATERIAL CHIP
J 0
(-1700 3800);
DISPLAY 0.489362 (-1700 3800);
PAINT SKYBLUE (-1700 3800);
DISPLAY INVISIBLE (-1700 3800);
FORCEPROP 1 LAST WATTAGE 1/16W
J 2
(-1725 3800);
DISPLAY 0.489362 (-1725 3800);
PAINT SKYBLUE (-1725 3800);
DISPLAY INVISIBLE (-1725 3800);
FORCEPROP 1 LAST PATH I285
J 0
(-2175 4025);
DISPLAY 0.978723 (-2175 4025);
PAINT WHITE (-2175 4025);
DISPLAY INVISIBLE (-2175 4025);
FORCEPROP 2 LAST CDS_LIB pure_quanta
J 0
(-2125 3875);
DISPLAY INVISIBLE (-2125 3875);
FORCEADD Q_RES..1
(-2125 3825);
FORCEPROP 1 LAST LOCATION R1348
J 0
(-2325 3825);
DISPLAY 0.489362 (-2325 3825);
PAINT SKYBLUE (-2325 3825);
FORCEPROP 0 LAST $SEC 1
J 0
(-2275 3875);
DISPLAY 0.680851 (-2275 3875);
PAINT MONO (-2275 3875);
DISPLAY INVISIBLE (-2275 3875);
FORCEPROP 0 LAST CDS_SEC 1
J 0
(-2275 3875);
DISPLAY 0.680851 (-2275 3875);
DISPLAY INVISIBLE (-2275 3875);
FORCEPROP 1 LASTPIN (-2225 3825) $PN 1
J 0
(-2213 3837);
DISPLAY 0.489362 (-2213 3837);
PAINT MONO (-2213 3837);
FORCEPROP 1 LASTPIN (-2025 3825) $PN 2
J 0
(-2063 3837);
DISPLAY 0.489362 (-2063 3837);
PAINT MONO (-2063 3837);
FORCEPROP 1 LAST VALUE 0
J 2
(-1975 3825);
DISPLAY 0.489362 (-1975 3825);
PAINT SKYBLUE (-1975 3825);
FORCEPROP 1 LAST PACK_TYPE 0402LF
J 0
(-2075 3750);
DISPLAY 0.489362 (-2075 3750);
PAINT SKYBLUE (-2075 3750);
DISPLAY INVISIBLE (-2075 3750);
FORCEPROP 1 LAST PART_NUMBER CS00002JB38
J 0
(-2100 3875);
DISPLAY 0.489362 (-2100 3875);
PAINT SKYBLUE (-2100 3875);
DISPLAY INVISIBLE (-2100 3875);
FORCEPROP 1 LAST TOLERANCE 5%
J 0
(-2150 3750);
DISPLAY 0.489362 (-2150 3750);
PAINT SKYBLUE (-2150 3750);
DISPLAY INVISIBLE (-2150 3750);
FORCEPROP 1 LAST MATERIAL CHIP
J 0
(-1700 3750);
DISPLAY 0.489362 (-1700 3750);
PAINT SKYBLUE (-1700 3750);
DISPLAY INVISIBLE (-1700 3750);
FORCEPROP 1 LAST WATTAGE 1/16W
J 2
(-1725 3750);
DISPLAY 0.489362 (-1725 3750);
PAINT SKYBLUE (-1725 3750);
DISPLAY INVISIBLE (-1725 3750);
FORCEPROP 1 LAST PATH I286
J 0
(-2175 3975);
DISPLAY 0.978723 (-2175 3975);
PAINT WHITE (-2175 3975);
DISPLAY INVISIBLE (-2175 3975);
FORCEPROP 2 LAST CDS_LIB pure_quanta
J 0
(-2125 3825);
DISPLAY INVISIBLE (-2125 3825);
FORCEADD Q_RES..1
(-2125 3525);
FORCEPROP 1 LAST LOCATION R1350
J 0
(-2325 3525);
DISPLAY 0.489362 (-2325 3525);
PAINT SKYBLUE (-2325 3525);
FORCEPROP 0 LAST $SEC 1
J 0
(-2275 3575);
DISPLAY 0.680851 (-2275 3575);
PAINT MONO (-2275 3575);
DISPLAY INVISIBLE (-2275 3575);
FORCEPROP 0 LAST CDS_SEC 1
J 0
(-2275 3575);
DISPLAY 0.680851 (-2275 3575);
DISPLAY INVISIBLE (-2275 3575);
FORCEPROP 1 LASTPIN (-2225 3525) $PN 1
J 0
(-2213 3537);
DISPLAY 0.489362 (-2213 3537);
PAINT MONO (-2213 3537);
FORCEPROP 1 LASTPIN (-2025 3525) $PN 2
J 0
(-2063 3537);
DISPLAY 0.489362 (-2063 3537);
PAINT MONO (-2063 3537);
FORCEPROP 1 LAST VALUE 0
J 2
(-1975 3525);
DISPLAY 0.489362 (-1975 3525);
PAINT SKYBLUE (-1975 3525);
FORCEPROP 1 LAST PACK_TYPE 0402LF
J 0
(-2075 3450);
DISPLAY 0.489362 (-2075 3450);
PAINT SKYBLUE (-2075 3450);
DISPLAY INVISIBLE (-2075 3450);
FORCEPROP 1 LAST PART_NUMBER CS00002JB38
J 0
(-2100 3575);
DISPLAY 0.489362 (-2100 3575);
PAINT SKYBLUE (-2100 3575);
DISPLAY INVISIBLE (-2100 3575);
FORCEPROP 1 LAST TOLERANCE 5%
J 0
(-2150 3450);
DISPLAY 0.489362 (-2150 3450);
PAINT SKYBLUE (-2150 3450);
DISPLAY INVISIBLE (-2150 3450);
FORCEPROP 1 LAST MATERIAL CHIP
J 0
(-1700 3450);
DISPLAY 0.489362 (-1700 3450);
PAINT SKYBLUE (-1700 3450);
DISPLAY INVISIBLE (-1700 3450);
FORCEPROP 1 LAST WATTAGE 1/16W
J 2
(-1725 3450);
DISPLAY 0.489362 (-1725 3450);
PAINT SKYBLUE (-1725 3450);
DISPLAY INVISIBLE (-1725 3450);
FORCEPROP 1 LAST PATH I287
J 0
(-2175 3675);
DISPLAY 0.978723 (-2175 3675);
PAINT WHITE (-2175 3675);
DISPLAY INVISIBLE (-2175 3675);
FORCEPROP 2 LAST CDS_LIB pure_quanta
J 0
(-2125 3525);
DISPLAY INVISIBLE (-2125 3525);
FORCEADD Q_RES..1
(-2125 3575);
FORCEPROP 1 LAST LOCATION R1349
J 0
(-2325 3575);
DISPLAY 0.489362 (-2325 3575);
PAINT SKYBLUE (-2325 3575);
FORCEPROP 0 LAST $SEC 1
J 0
(-2275 3625);
DISPLAY 0.680851 (-2275 3625);
PAINT MONO (-2275 3625);
DISPLAY INVISIBLE (-2275 3625);
FORCEPROP 0 LAST CDS_SEC 1
J 0
(-2275 3625);
DISPLAY 0.680851 (-2275 3625);
DISPLAY INVISIBLE (-2275 3625);
FORCEPROP 1 LASTPIN (-2225 3575) $PN 1
J 0
(-2213 3587);
DISPLAY 0.489362 (-2213 3587);
PAINT MONO (-2213 3587);
FORCEPROP 1 LASTPIN (-2025 3575) $PN 2
J 0
(-2063 3587);
DISPLAY 0.489362 (-2063 3587);
PAINT MONO (-2063 3587);
FORCEPROP 1 LAST VALUE 0
J 2
(-1975 3575);
DISPLAY 0.489362 (-1975 3575);
PAINT SKYBLUE (-1975 3575);
FORCEPROP 1 LAST PACK_TYPE 0402LF
J 0
(-2075 3500);
DISPLAY 0.489362 (-2075 3500);
PAINT SKYBLUE (-2075 3500);
DISPLAY INVISIBLE (-2075 3500);
FORCEPROP 1 LAST PART_NUMBER CS00002JB38
J 0
(-2100 3625);
DISPLAY 0.489362 (-2100 3625);
PAINT SKYBLUE (-2100 3625);
DISPLAY INVISIBLE (-2100 3625);
FORCEPROP 1 LAST TOLERANCE 5%
J 0
(-2150 3500);
DISPLAY 0.489362 (-2150 3500);
PAINT SKYBLUE (-2150 3500);
DISPLAY INVISIBLE (-2150 3500);
FORCEPROP 1 LAST MATERIAL CHIP
J 0
(-1700 3500);
DISPLAY 0.489362 (-1700 3500);
PAINT SKYBLUE (-1700 3500);
DISPLAY INVISIBLE (-1700 3500);
FORCEPROP 1 LAST WATTAGE 1/16W
J 2
(-1725 3500);
DISPLAY 0.489362 (-1725 3500);
PAINT SKYBLUE (-1725 3500);
DISPLAY INVISIBLE (-1725 3500);
FORCEPROP 1 LAST PATH I288
J 0
(-2175 3725);
DISPLAY 0.978723 (-2175 3725);
PAINT WHITE (-2175 3725);
DISPLAY INVISIBLE (-2175 3725);
FORCEPROP 2 LAST CDS_LIB pure_quanta
J 0
(-2125 3575);
DISPLAY INVISIBLE (-2125 3575);
FORCEADD Q_RES..1
(-8625 1925);
FORCEPROP 1 LAST LOCATION R556
J 0
(-8350 1925);
DISPLAY 0.489362 (-8350 1925);
PAINT SKYBLUE (-8350 1925);
FORCEPROP 0 LAST $SEC 1
J 0
(-8350 1950);
DISPLAY 0.680851 (-8350 1950);
PAINT MONO (-8350 1950);
DISPLAY INVISIBLE (-8350 1950);
FORCEPROP 0 LAST CDS_SEC 1
J 0
(-8350 1950);
DISPLAY 0.680851 (-8350 1950);
DISPLAY INVISIBLE (-8350 1950);
FORCEPROP 1 LASTPIN (-8725 1925) $PN 1
J 0
(-8713 1937);
DISPLAY 0.489362 (-8713 1937);
PAINT MONO (-8713 1937);
FORCEPROP 1 LASTPIN (-8525 1925) $PN 2
J 0
(-8563 1937);
DISPLAY 0.489362 (-8563 1937);
PAINT MONO (-8563 1937);
FORCEPROP 1 LAST MATERIAL EMPTY
J 0
(-8525 1925);
DISPLAY 0.510638 (-8525 1925);
PAINT RED (-8525 1925);
FORCEPROP 1 LAST VALUE 1K
J 0
(-8875 1925);
DISPLAY 0.489362 (-8875 1925);
PAINT SKYBLUE (-8875 1925);
FORCEPROP 1 LAST PACK_TYPE 0402LF
J 0
(-8375 1775);
DISPLAY 0.978723 (-8375 1775);
PAINT SKYBLUE (-8375 1775);
DISPLAY INVISIBLE (-8375 1775);
FORCEPROP 1 LAST PART_NUMBER TMP_QCS21002JB34
J 0
(-8675 2025);
DISPLAY 0.978723 (-8675 2025);
PAINT SKYBLUE (-8675 2025);
DISPLAY INVISIBLE (-8675 2025);
FORCEPROP 1 LAST TOLERANCE 5%
J 0
(-8625 1825);
DISPLAY 0.978723 (-8625 1825);
PAINT SKYBLUE (-8625 1825);
DISPLAY INVISIBLE (-8625 1825);
FORCEPROP 1 LAST WATTAGE 1/16W
J 2
(-8650 1775);
DISPLAY 0.978723 (-8650 1775);
PAINT SKYBLUE (-8650 1775);
DISPLAY INVISIBLE (-8650 1775);
FORCEPROP 1 LAST PATH I289
J 0
(-8675 2075);
DISPLAY 0.978723 (-8675 2075);
PAINT WHITE (-8675 2075);
DISPLAY INVISIBLE (-8675 2075);
FORCEPROP 2 LAST CDS_LIB pure_quanta
J 0
(-8625 1925);
DISPLAY INVISIBLE (-8625 1925);
FORCEADD Q_RES..1
(-8625 1825);
FORCEPROP 1 LAST LOCATION R559
J 0
(-8350 1825);
DISPLAY 0.489362 (-8350 1825);
PAINT SKYBLUE (-8350 1825);
FORCEPROP 0 LAST $SEC 1
J 0
(-8350 1850);
DISPLAY 0.680851 (-8350 1850);
PAINT MONO (-8350 1850);
DISPLAY INVISIBLE (-8350 1850);
FORCEPROP 0 LAST CDS_SEC 1
J 0
(-8350 1850);
DISPLAY 0.680851 (-8350 1850);
DISPLAY INVISIBLE (-8350 1850);
FORCEPROP 1 LASTPIN (-8725 1825) $PN 1
J 0
(-8713 1837);
DISPLAY 0.489362 (-8713 1837);
PAINT MONO (-8713 1837);
FORCEPROP 1 LASTPIN (-8525 1825) $PN 2
J 0
(-8563 1837);
DISPLAY 0.489362 (-8563 1837);
PAINT MONO (-8563 1837);
FORCEPROP 1 LAST VALUE 2.2K
J 0
(-8875 1825);
DISPLAY 0.489362 (-8875 1825);
PAINT SKYBLUE (-8875 1825);
FORCEPROP 1 LAST PACK_TYPE 0402LF
J 0
(-8375 1675);
DISPLAY 0.978723 (-8375 1675);
PAINT SKYBLUE (-8375 1675);
DISPLAY INVISIBLE (-8375 1675);
FORCEPROP 1 LAST PART_NUMBER CS22202JB07
J 0
(-8675 1925);
DISPLAY 0.978723 (-8675 1925);
PAINT SKYBLUE (-8675 1925);
DISPLAY INVISIBLE (-8675 1925);
FORCEPROP 1 LAST TOLERANCE 5%
J 0
(-8625 1725);
DISPLAY 0.978723 (-8625 1725);
PAINT SKYBLUE (-8625 1725);
DISPLAY INVISIBLE (-8625 1725);
FORCEPROP 1 LAST MATERIAL CHIP
J 0
(-8625 1675);
DISPLAY 0.978723 (-8625 1675);
PAINT SKYBLUE (-8625 1675);
DISPLAY INVISIBLE (-8625 1675);
FORCEPROP 1 LAST WATTAGE 1/16W
J 2
(-8650 1675);
DISPLAY 0.978723 (-8650 1675);
PAINT SKYBLUE (-8650 1675);
DISPLAY INVISIBLE (-8650 1675);
FORCEPROP 1 LAST PATH I290
J 0
(-8675 1975);
DISPLAY 0.978723 (-8675 1975);
PAINT WHITE (-8675 1975);
DISPLAY INVISIBLE (-8675 1975);
FORCEPROP 2 LAST CDS_LIB pure_quanta
J 0
(-8625 1825);
DISPLAY INVISIBLE (-8625 1825);
FORCEADD UNIVERSAL_POWER..1
R 2
(-7375 4975);
FORCEPROP 3 LASTPIN (-7375 4925) SIG_NAME PVDD18_S5_P1\g
J 0
(-7365 4935);
DISPLAY 0.659574 (-7365 4935);
PAINT MONO (-7365 4935);
DISPLAY INVISIBLE (-7365 4935);
FORCEPROP 1 LAST HDL_POWER PVDD18_S5_P1
J 1
(-7350 5025);
DISPLAY 0.489362 (-7350 5025);
PAINT GREEN (-7350 5025);
FORCEPROP 1 LAST PATH I291
J 2
(-7425 5000);
DISPLAY 0.872340 (-7425 5000);
PAINT AQUA (-7425 5000);
DISPLAY INVISIBLE (-7425 5000);
FORCEPROP 2 LAST CDS_LIB pure_quanta_power
J 0
(-7375 4975);
DISPLAY INVISIBLE (-7375 4975);
FORCEADD Q_RES..1
(-7050 4875);
FORCEPROP 1 LAST LOCATION R1424
J 2
(-6900 4875);
DISPLAY 0.489362 (-6900 4875);
PAINT SKYBLUE (-6900 4875);
FORCEPROP 0 LAST $SEC 1
J 0
(-6900 4900);
DISPLAY 0.680851 (-6900 4900);
PAINT MONO (-6900 4900);
DISPLAY INVISIBLE (-6900 4900);
FORCEPROP 0 LAST CDS_SEC 1
J 0
(-6900 4900);
DISPLAY 0.680851 (-6900 4900);
DISPLAY INVISIBLE (-6900 4900);
FORCEPROP 1 LASTPIN (-7150 4875) $PN 1
J 0
(-7138 4887);
DISPLAY 0.489362 (-7138 4887);
PAINT MONO (-7138 4887);
FORCEPROP 1 LASTPIN (-6950 4875) $PN 2
J 0
(-6988 4887);
DISPLAY 0.489362 (-6988 4887);
PAINT MONO (-6988 4887);
FORCEPROP 1 LAST VALUE 2.2K
J 0
(-7300 4875);
DISPLAY 0.489362 (-7300 4875);
PAINT SKYBLUE (-7300 4875);
FORCEPROP 1 LAST PACK_TYPE 0402LF
J 0
(-6800 4725);
DISPLAY 0.978723 (-6800 4725);
PAINT SKYBLUE (-6800 4725);
DISPLAY INVISIBLE (-6800 4725);
FORCEPROP 1 LAST PART_NUMBER CS22202JB07
J 0
(-7100 4975);
DISPLAY 0.978723 (-7100 4975);
PAINT SKYBLUE (-7100 4975);
DISPLAY INVISIBLE (-7100 4975);
FORCEPROP 1 LAST TOLERANCE 5%
J 0
(-7050 4775);
DISPLAY 0.978723 (-7050 4775);
PAINT SKYBLUE (-7050 4775);
DISPLAY INVISIBLE (-7050 4775);
FORCEPROP 1 LAST MATERIAL CHIP
J 0
(-7050 4725);
DISPLAY 0.978723 (-7050 4725);
PAINT SKYBLUE (-7050 4725);
DISPLAY INVISIBLE (-7050 4725);
FORCEPROP 1 LAST WATTAGE 1/16W
J 2
(-7075 4725);
DISPLAY 0.978723 (-7075 4725);
PAINT SKYBLUE (-7075 4725);
DISPLAY INVISIBLE (-7075 4725);
FORCEPROP 1 LAST PATH I292
J 0
(-7100 5025);
DISPLAY 0.978723 (-7100 5025);
PAINT WHITE (-7100 5025);
DISPLAY INVISIBLE (-7100 5025);
FORCEPROP 2 LAST CDS_LIB pure_quanta
J 0
(-7050 4875);
DISPLAY INVISIBLE (-7050 4875);
FORCEADD Q_RES..1
R 2
(-8625 1675);
FORCEPROP 1 LAST LOCATION R561
J 0
(-8350 1675);
DISPLAY 0.489362 (-8350 1675);
PAINT SKYBLUE (-8350 1675);
FORCEPROP 0 LAST $SEC 1
J 0
(-8350 1700);
DISPLAY 0.680851 (-8350 1700);
PAINT MONO (-8350 1700);
DISPLAY INVISIBLE (-8350 1700);
FORCEPROP 0 LAST CDS_SEC 1
J 0
(-8350 1700);
DISPLAY 0.680851 (-8350 1700);
DISPLAY INVISIBLE (-8350 1700);
FORCEPROP 1 LASTPIN (-8525 1675) $PN 1
J 2
(-8537 1687);
DISPLAY 0.489362 (-8537 1687);
PAINT MONO (-8537 1687);
FORCEPROP 1 LASTPIN (-8725 1675) $PN 2
J 2
(-8687 1687);
DISPLAY 0.489362 (-8687 1687);
PAINT MONO (-8687 1687);
FORCEPROP 1 LAST MATERIAL EMPTY
J 0
(-8500 1675);
DISPLAY 0.489362 (-8500 1675);
PAINT RED (-8500 1675);
FORCEPROP 1 LAST VALUE 4.7K
J 0
(-8875 1675);
DISPLAY 0.489362 (-8875 1675);
PAINT SKYBLUE (-8875 1675);
FORCEPROP 1 LAST PACK_TYPE 0402LF
J 2
(-8875 1525);
DISPLAY 0.510638 (-8875 1525);
PAINT SKYBLUE (-8875 1525);
DISPLAY INVISIBLE (-8875 1525);
FORCEPROP 1 LAST PART_NUMBER TMP_QCS24702JB38
J 2
(-8575 1775);
DISPLAY 0.510638 (-8575 1775);
PAINT SKYBLUE (-8575 1775);
DISPLAY INVISIBLE (-8575 1775);
FORCEPROP 1 LAST TOLERANCE 5%
J 2
(-8750 1675);
DISPLAY 0.510638 (-8750 1675);
PAINT SKYBLUE (-8750 1675);
DISPLAY INVISIBLE (-8750 1675);
FORCEPROP 1 LAST WATTAGE 1/16W
J 0
(-8600 1525);
DISPLAY 0.510638 (-8600 1525);
PAINT SKYBLUE (-8600 1525);
DISPLAY INVISIBLE (-8600 1525);
FORCEPROP 1 LAST PATH I293
J 2
(-8575 1825);
DISPLAY 0.978723 (-8575 1825);
PAINT WHITE (-8575 1825);
DISPLAY INVISIBLE (-8575 1825);
FORCEPROP 2 LAST CDS_LIB pure_quanta
J 0
(-8625 1675);
DISPLAY INVISIBLE (-8625 1675);
FORCEADD Q_RES..1
(-8625 2125);
FORCEPROP 1 LAST LOCATION R557
J 0
(-8350 2125);
DISPLAY 0.489362 (-8350 2125);
PAINT SKYBLUE (-8350 2125);
FORCEPROP 0 LAST $SEC 1
J 0
(-8350 2150);
DISPLAY 0.680851 (-8350 2150);
PAINT MONO (-8350 2150);
DISPLAY INVISIBLE (-8350 2150);
FORCEPROP 0 LAST CDS_SEC 1
J 0
(-8350 2150);
DISPLAY 0.680851 (-8350 2150);
DISPLAY INVISIBLE (-8350 2150);
FORCEPROP 1 LASTPIN (-8725 2125) $PN 1
J 0
(-8713 2137);
DISPLAY 0.489362 (-8713 2137);
PAINT MONO (-8713 2137);
FORCEPROP 1 LASTPIN (-8525 2125) $PN 2
J 0
(-8563 2137);
DISPLAY 0.489362 (-8563 2137);
PAINT MONO (-8563 2137);
FORCEPROP 1 LAST VALUE 1K
J 0
(-8875 2125);
DISPLAY 0.489362 (-8875 2125);
PAINT SKYBLUE (-8875 2125);
FORCEPROP 1 LAST MATERIAL EMPTY
J 0
(-8525 2125);
DISPLAY 0.510638 (-8525 2125);
PAINT RED (-8525 2125);
FORCEPROP 2 LAST CDS_LIB pure_quanta
J 0
(-8625 2125);
DISPLAY INVISIBLE (-8625 2125);
FORCEPROP 1 LAST PATH I294
J 0
(-8675 2275);
DISPLAY 0.978723 (-8675 2275);
PAINT WHITE (-8675 2275);
DISPLAY INVISIBLE (-8675 2275);
FORCEPROP 1 LAST WATTAGE 1/16W
J 2
(-8650 1975);
DISPLAY 0.978723 (-8650 1975);
PAINT SKYBLUE (-8650 1975);
DISPLAY INVISIBLE (-8650 1975);
FORCEPROP 1 LAST TOLERANCE 5%
J 0
(-8625 2025);
DISPLAY 0.978723 (-8625 2025);
PAINT SKYBLUE (-8625 2025);
DISPLAY INVISIBLE (-8625 2025);
FORCEPROP 1 LAST PART_NUMBER TMP_QCS21002JB34
J 0
(-8675 2225);
DISPLAY 0.978723 (-8675 2225);
PAINT SKYBLUE (-8675 2225);
DISPLAY INVISIBLE (-8675 2225);
FORCEPROP 1 LAST PACK_TYPE 0402LF
J 0
(-8375 1975);
DISPLAY 0.978723 (-8375 1975);
PAINT SKYBLUE (-8375 1975);
DISPLAY INVISIBLE (-8375 1975);
FORCEADD Q_RES..1
(-8625 1775);
FORCEPROP 1 LAST LOCATION R562
J 0
(-8350 1775);
DISPLAY 0.489362 (-8350 1775);
PAINT SKYBLUE (-8350 1775);
FORCEPROP 0 LAST $SEC 1
J 0
(-8350 1800);
DISPLAY 0.680851 (-8350 1800);
PAINT MONO (-8350 1800);
DISPLAY INVISIBLE (-8350 1800);
FORCEPROP 0 LAST CDS_SEC 1
J 0
(-8350 1800);
DISPLAY 0.680851 (-8350 1800);
DISPLAY INVISIBLE (-8350 1800);
FORCEPROP 1 LASTPIN (-8725 1775) $PN 1
J 0
(-8713 1787);
DISPLAY 0.489362 (-8713 1787);
PAINT MONO (-8713 1787);
FORCEPROP 1 LASTPIN (-8525 1775) $PN 2
J 0
(-8563 1787);
DISPLAY 0.489362 (-8563 1787);
PAINT MONO (-8563 1787);
FORCEPROP 1 LAST VALUE 2.2K
J 0
(-8875 1775);
DISPLAY 0.489362 (-8875 1775);
PAINT SKYBLUE (-8875 1775);
FORCEPROP 1 LAST PACK_TYPE 0402LF
J 0
(-8375 1625);
DISPLAY 0.978723 (-8375 1625);
PAINT SKYBLUE (-8375 1625);
DISPLAY INVISIBLE (-8375 1625);
FORCEPROP 1 LAST PART_NUMBER CS22202JB07
J 0
(-8675 1875);
DISPLAY 0.978723 (-8675 1875);
PAINT SKYBLUE (-8675 1875);
DISPLAY INVISIBLE (-8675 1875);
FORCEPROP 1 LAST TOLERANCE 5%
J 0
(-8625 1675);
DISPLAY 0.978723 (-8625 1675);
PAINT SKYBLUE (-8625 1675);
DISPLAY INVISIBLE (-8625 1675);
FORCEPROP 1 LAST MATERIAL CHIP
J 0
(-8625 1625);
DISPLAY 0.978723 (-8625 1625);
PAINT SKYBLUE (-8625 1625);
DISPLAY INVISIBLE (-8625 1625);
FORCEPROP 1 LAST WATTAGE 1/16W
J 2
(-8650 1625);
DISPLAY 0.978723 (-8650 1625);
PAINT SKYBLUE (-8650 1625);
DISPLAY INVISIBLE (-8650 1625);
FORCEPROP 1 LAST PATH I295
J 0
(-8675 1925);
DISPLAY 0.978723 (-8675 1925);
PAINT WHITE (-8675 1925);
DISPLAY INVISIBLE (-8675 1925);
FORCEPROP 2 LAST CDS_LIB pure_quanta
J 0
(-8625 1775);
DISPLAY INVISIBLE (-8625 1775);
FORCEADD Q_RES..1
(-2250 2125);
FORCEPROP 1 LAST LOCATION R575
J 0
(-2575 2125);
DISPLAY 0.489362 (-2575 2125);
PAINT SKYBLUE (-2575 2125);
FORCEPROP 0 LAST $SEC 1
J 0
(-2050 2150);
DISPLAY 0.680851 (-2050 2150);
PAINT MONO (-2050 2150);
DISPLAY INVISIBLE (-2050 2150);
FORCEPROP 0 LAST CDS_SEC 1
J 0
(-2050 2150);
DISPLAY 0.680851 (-2050 2150);
DISPLAY INVISIBLE (-2050 2150);
FORCEPROP 1 LASTPIN (-2350 2125) $PN 1
J 0
(-2338 2137);
DISPLAY 0.489362 (-2338 2137);
PAINT MONO (-2338 2137);
FORCEPROP 1 LASTPIN (-2150 2125) $PN 2
J 0
(-2188 2137);
DISPLAY 0.489362 (-2188 2137);
PAINT MONO (-2188 2137);
FORCEPROP 1 LAST VALUE 0
J 2
(-2050 2125);
DISPLAY 0.489362 (-2050 2125);
PAINT SKYBLUE (-2050 2125);
FORCEPROP 1 LAST MATERIAL EMPTY
J 0
(-2450 2125);
DISPLAY 0.489362 (-2450 2125);
PAINT RED (-2450 2125);
FORCEPROP 1 LAST PACK_TYPE 0402LF
J 0
(-1800 2200);
DISPLAY 0.489362 (-1800 2200);
PAINT SKYBLUE (-1800 2200);
DISPLAY INVISIBLE (-1800 2200);
FORCEPROP 1 LAST PART_NUMBER CS00002JB38
J 0
(-2425 2250);
DISPLAY 0.489362 (-2425 2250);
PAINT SKYBLUE (-2425 2250);
DISPLAY INVISIBLE (-2425 2250);
FORCEPROP 1 LAST TOLERANCE 5%
J 0
(-2425 2200);
DISPLAY 0.489362 (-2425 2200);
PAINT SKYBLUE (-2425 2200);
DISPLAY INVISIBLE (-2425 2200);
FORCEPROP 1 LAST WATTAGE 1/16W
J 2
(-2075 2200);
DISPLAY 0.489362 (-2075 2200);
PAINT SKYBLUE (-2075 2200);
DISPLAY INVISIBLE (-2075 2200);
FORCEPROP 1 LAST PATH I296
J 0
(-2300 2275);
DISPLAY 0.978723 (-2300 2275);
PAINT WHITE (-2300 2275);
DISPLAY INVISIBLE (-2300 2275);
FORCEPROP 2 LAST CDS_LIB pure_quanta
J 0
(-2250 2125);
DISPLAY INVISIBLE (-2250 2125);
FORCEADD Q_RES..1
(-6625 5775);
FORCEPROP 1 LAST LOCATION R191
J 0
(-6500 5775);
DISPLAY 0.489362 (-6500 5775);
PAINT SKYBLUE (-6500 5775);
FORCEPROP 0 LAST $SEC 1
J 2
(-6500 5825);
DISPLAY 0.680851 (-6500 5825);
PAINT MONO (-6500 5825);
DISPLAY INVISIBLE (-6500 5825);
FORCEPROP 0 LAST CDS_SEC 1
J 2
(-6500 5825);
DISPLAY 1.021277 (-6500 5825);
DISPLAY INVISIBLE (-6500 5825);
FORCEPROP 1 LASTPIN (-6725 5775) $PN 1
J 0
(-6713 5787);
DISPLAY 0.489362 (-6713 5787);
PAINT MONO (-6713 5787);
FORCEPROP 1 LASTPIN (-6525 5775) $PN 2
J 0
(-6563 5787);
DISPLAY 0.489362 (-6563 5787);
PAINT MONO (-6563 5787);
FORCEPROP 1 LAST VALUE 0
J 2
(-6750 5775);
DISPLAY 0.489362 (-6750 5775);
PAINT SKYBLUE (-6750 5775);
FORCEPROP 1 LAST MATERIAL EMPTY
J 2
(-6800 5775);
DISPLAY 0.489362 (-6800 5775);
PAINT RED (-6800 5775);
FORCEPROP 2 LAST ROOM RST_CPU0_PLD_TO_DIMM
J 2
(-6600 5875);
DISPLAY 0.744681 (-6600 5875);
PAINT RED (-6600 5875);
DISPLAY INVISIBLE (-6600 5875);
FORCEPROP 1 LAST PACK_TYPE 0402LF
J 2
(-6450 5700);
DISPLAY 0.489362 (-6450 5700);
PAINT SKYBLUE (-6450 5700);
DISPLAY INVISIBLE (-6450 5700);
FORCEPROP 1 LAST PART_NUMBER CS00002JB38
J 2
(-6525 5825);
DISPLAY 0.489362 (-6525 5825);
PAINT SKYBLUE (-6525 5825);
DISPLAY INVISIBLE (-6525 5825);
FORCEPROP 1 LAST TOLERANCE 5%
J 0
(-6750 5750);
DISPLAY 0.489362 (-6750 5750);
PAINT SKYBLUE (-6750 5750);
DISPLAY INVISIBLE (-6750 5750);
FORCEPROP 1 LAST WATTAGE 1/16W
J 2
(-6700 5700);
DISPLAY 0.489362 (-6700 5700);
PAINT SKYBLUE (-6700 5700);
DISPLAY INVISIBLE (-6700 5700);
FORCEPROP 1 LAST PATH I297
J 0
(-6675 5925);
DISPLAY 0.978723 (-6675 5925);
PAINT WHITE (-6675 5925);
DISPLAY INVISIBLE (-6675 5925);
FORCEPROP 2 LAST CDS_LIB pure_quanta
J 2
(-6625 5775);
DISPLAY INVISIBLE (-6625 5775);
FORCEPROP 2 LAST BOM_COST MEM
J 2
(-6600 5925);
DISPLAY 0.744681 (-6600 5925);
PAINT WHITE (-6600 5925);
DISPLAY INVISIBLE (-6600 5925);
FORCEADD Q_RES..1
(-6625 5725);
FORCEPROP 1 LAST LOCATION R192
J 0
(-6500 5725);
DISPLAY 0.489362 (-6500 5725);
PAINT SKYBLUE (-6500 5725);
FORCEPROP 0 LAST $SEC 1
J 2
(-6500 5775);
DISPLAY 0.680851 (-6500 5775);
PAINT MONO (-6500 5775);
DISPLAY INVISIBLE (-6500 5775);
FORCEPROP 0 LAST CDS_SEC 1
J 2
(-6500 5775);
DISPLAY 1.021277 (-6500 5775);
DISPLAY INVISIBLE (-6500 5775);
FORCEPROP 1 LASTPIN (-6725 5725) $PN 1
J 0
(-6713 5737);
DISPLAY 0.489362 (-6713 5737);
PAINT MONO (-6713 5737);
FORCEPROP 1 LASTPIN (-6525 5725) $PN 2
J 0
(-6563 5737);
DISPLAY 0.489362 (-6563 5737);
PAINT MONO (-6563 5737);
FORCEPROP 1 LAST VALUE 0
J 2
(-6750 5725);
DISPLAY 0.489362 (-6750 5725);
PAINT SKYBLUE (-6750 5725);
FORCEPROP 1 LAST MATERIAL EMPTY
J 2
(-6800 5725);
DISPLAY 0.489362 (-6800 5725);
PAINT RED (-6800 5725);
FORCEPROP 2 LAST ROOM RST_CPU0_PLD_TO_DIMM
J 2
(-6600 5825);
DISPLAY 0.744681 (-6600 5825);
PAINT RED (-6600 5825);
DISPLAY INVISIBLE (-6600 5825);
FORCEPROP 1 LAST PACK_TYPE 0402LF
J 2
(-6450 5650);
DISPLAY 0.489362 (-6450 5650);
PAINT SKYBLUE (-6450 5650);
DISPLAY INVISIBLE (-6450 5650);
FORCEPROP 1 LAST PART_NUMBER CS00002JB38
J 2
(-6525 5775);
DISPLAY 0.489362 (-6525 5775);
PAINT SKYBLUE (-6525 5775);
DISPLAY INVISIBLE (-6525 5775);
FORCEPROP 1 LAST TOLERANCE 5%
J 0
(-6750 5700);
DISPLAY 0.489362 (-6750 5700);
PAINT SKYBLUE (-6750 5700);
DISPLAY INVISIBLE (-6750 5700);
FORCEPROP 1 LAST WATTAGE 1/16W
J 2
(-6700 5650);
DISPLAY 0.489362 (-6700 5650);
PAINT SKYBLUE (-6700 5650);
DISPLAY INVISIBLE (-6700 5650);
FORCEPROP 1 LAST PATH I298
J 0
(-6675 5875);
DISPLAY 0.978723 (-6675 5875);
PAINT WHITE (-6675 5875);
DISPLAY INVISIBLE (-6675 5875);
FORCEPROP 2 LAST CDS_LIB pure_quanta
J 2
(-6625 5725);
DISPLAY INVISIBLE (-6625 5725);
FORCEPROP 2 LAST BOM_COST MEM
J 2
(-6600 5875);
DISPLAY 0.744681 (-6600 5875);
PAINT WHITE (-6600 5875);
DISPLAY INVISIBLE (-6600 5875);
FORCEADD OFFPAGE..2
R 2
(-7625 5775);
FORCEPROP 2 LAST $XR0 80 
J 0
(-7879 5775);
DISPLAY 0.638298 (-7879 5775);
PAINT MONO (-7879 5775);
FORCEPROP 1 LAST COMMENT_BODY TRUE
J 2
(-7580 5680);
DISPLAY 0.872340 (-7580 5680);
PAINT GREEN (-7580 5680);
DISPLAY INVISIBLE (-7580 5680);
FORCEPROP 1 LAST OFFPAGE TRUE
J 2
(-7950 5650);
DISPLAY 0.872340 (-7950 5650);
PAINT GREEN (-7950 5650);
DISPLAY INVISIBLE (-7950 5650);
FORCEPROP 2 LAST CDS_LIB standard
J 0
(-7625 5775);
DISPLAY INVISIBLE (-7625 5775);
FORCEPROP 2 LAST PATH I299
J 0
(-7825 5825);
DISPLAY 0.680851 (-7825 5825);
DISPLAY INVISIBLE (-7825 5825);
FORCEADD Q_CAP..1
(-6175 825);
FORCEPROP 1 LAST LOCATION C236
J 0
(-6125 925);
DISPLAY 0.489362 (-6125 925);
PAINT SKYBLUE (-6125 925);
FORCEPROP 0 LAST $SEC 1
J 0
(-6125 975);
DISPLAY 0.680851 (-6125 975);
PAINT MONO (-6125 975);
DISPLAY INVISIBLE (-6125 975);
FORCEPROP 0 LAST CDS_SEC 1
J 0
(-6125 975);
DISPLAY 1.021277 (-6125 975);
DISPLAY INVISIBLE (-6125 975);
FORCEPROP 1 LASTPIN (-6175 925) $PN 1
J 0
(-6165 905);
DISPLAY 0.489362 (-6165 905);
PAINT MONO (-6165 905);
FORCEPROP 1 LASTPIN (-6175 725) $PN 2
J 0
(-6165 705);
DISPLAY 0.489362 (-6165 705);
PAINT MONO (-6165 705);
FORCEPROP 1 LAST PACK_TYPE C0402
J 0
(-6125 625);
DISPLAY 0.489362 (-6125 625);
PAINT SKYBLUE (-6125 625);
FORCEPROP 1 LAST VOLTAGE 50V
J 0
(-6125 825);
DISPLAY 0.489362 (-6125 825);
PAINT SKYBLUE (-6125 825);
FORCEPROP 1 LAST PART_NUMBER CH-3916TB01
J 0
(-6125 675);
DISPLAY 0.489362 (-6125 675);
PAINT SKYBLUE (-6125 675);
FORCEPROP 1 LAST VALUE 3.9P
J 0
(-6125 875);
DISPLAY 0.489362 (-6125 875);
PAINT SKYBLUE (-6125 875);
FORCEPROP 1 LAST TOLERANCE 0.1P
J 0
(-6125 775);
DISPLAY 0.489362 (-6125 775);
PAINT SKYBLUE (-6125 775);
FORCEPROP 1 LAST MATERIAL NPO
J 0
(-6125 725);
DISPLAY 0.489362 (-6125 725);
PAINT SKYBLUE (-6125 725);
FORCEPROP 1 LAST PATH I3
J 0
(-6125 975);
DISPLAY 0.978723 (-6125 975);
PAINT WHITE (-6125 975);
DISPLAY INVISIBLE (-6125 975);
FORCEPROP 2 LAST CDS_LIB pure_quanta
J 0
(-6175 825);
DISPLAY INVISIBLE (-6175 825);
FORCEADD OFFPAGE..2
R 2
(-7625 5725);
FORCEPROP 2 LAST $XR0 80 
J 0
(-7879 5725);
DISPLAY 0.638298 (-7879 5725);
PAINT MONO (-7879 5725);
FORCEPROP 1 LAST COMMENT_BODY TRUE
J 2
(-7580 5630);
DISPLAY 0.872340 (-7580 5630);
PAINT GREEN (-7580 5630);
DISPLAY INVISIBLE (-7580 5630);
FORCEPROP 1 LAST OFFPAGE TRUE
J 2
(-7950 5600);
DISPLAY 0.872340 (-7950 5600);
PAINT GREEN (-7950 5600);
DISPLAY INVISIBLE (-7950 5600);
FORCEPROP 2 LAST CDS_LIB standard
J 0
(-7625 5725);
DISPLAY INVISIBLE (-7625 5725);
FORCEPROP 2 LAST PATH I300
J 0
(-7825 5775);
DISPLAY 0.680851 (-7825 5775);
DISPLAY INVISIBLE (-7825 5775);
FORCEADD OFFPAGE..2
(-2175 5975);
FORCEPROP 2 LAST $XR0 75 
J 0
(-1986 5975);
DISPLAY 0.638298 (-1986 5975);
PAINT MONO (-1986 5975);
FORCEPROP 2 LAST PATH I301
J 0
(-1875 6025);
DISPLAY 0.680851 (-1875 6025);
DISPLAY INVISIBLE (-1875 6025);
FORCEPROP 1 LAST COMMENT_BODY TRUE
J 0
(-2220 5880);
DISPLAY 0.872340 (-2220 5880);
PAINT GREEN (-2220 5880);
DISPLAY INVISIBLE (-2220 5880);
FORCEPROP 1 LAST OFFPAGE TRUE
J 0
(-1850 5850);
DISPLAY 0.872340 (-1850 5850);
PAINT GREEN (-1850 5850);
DISPLAY INVISIBLE (-1850 5850);
FORCEPROP 2 LAST CDS_LIB standard
J 0
(-2175 5975);
DISPLAY INVISIBLE (-2175 5975);
FORCEADD UNIVERSAL_GND..1
(-4125 650);
FORCEPROP 3 LASTPIN (-4125 700) SIG_NAME GND\g
J 0
(-4115 710);
DISPLAY 0.659574 (-4115 710);
PAINT MONO (-4115 710);
DISPLAY INVISIBLE (-4115 710);
FORCEPROP 1 LAST HDL_POWER GND
J 1
(-4100 575);
DISPLAY 0.872340 (-4100 575);
PAINT GREEN (-4100 575);
DISPLAY INVISIBLE (-4100 575);
FORCEPROP 1 LAST PATH I4
J 0
(-4050 650);
DISPLAY 0.872340 (-4050 650);
PAINT AQUA (-4050 650);
DISPLAY INVISIBLE (-4050 650);
FORCEPROP 2 LAST CDS_LIB pure_quanta_power
J 0
(-4125 650);
DISPLAY INVISIBLE (-4125 650);
FORCEADD Q_CAP..1
(-4125 1050);
FORCEPROP 1 LAST LOCATION C238
J 0
(-4075 1150);
DISPLAY 0.489362 (-4075 1150);
PAINT SKYBLUE (-4075 1150);
FORCEPROP 0 LAST $SEC 1
J 0
(-4075 1200);
DISPLAY 0.680851 (-4075 1200);
PAINT MONO (-4075 1200);
DISPLAY INVISIBLE (-4075 1200);
FORCEPROP 0 LAST CDS_SEC 1
J 0
(-4075 1200);
DISPLAY 1.021277 (-4075 1200);
DISPLAY INVISIBLE (-4075 1200);
FORCEPROP 1 LASTPIN (-4125 1150) $PN 1
J 0
(-4115 1130);
DISPLAY 0.489362 (-4115 1130);
PAINT MONO (-4115 1130);
FORCEPROP 1 LASTPIN (-4125 950) $PN 2
J 0
(-4115 930);
DISPLAY 0.489362 (-4115 930);
PAINT MONO (-4115 930);
FORCEPROP 1 LAST VALUE 10PF
J 0
(-4075 1100);
DISPLAY 0.489362 (-4075 1100);
PAINT SKYBLUE (-4075 1100);
FORCEPROP 1 LAST VOLTAGE 50V
J 0
(-4075 1050);
DISPLAY 0.489362 (-4075 1050);
PAINT SKYBLUE (-4075 1050);
FORCEPROP 1 LAST PACK_TYPE 0402
J 0
(-4075 850);
DISPLAY 0.489362 (-4075 850);
PAINT SKYBLUE (-4075 850);
FORCEPROP 1 LAST MATERIAL NPO
J 0
(-4075 950);
DISPLAY 0.489362 (-4075 950);
PAINT SKYBLUE (-4075 950);
FORCEPROP 1 LAST TOLERANCE 1%
J 0
(-4075 1000);
DISPLAY 0.489362 (-4075 1000);
PAINT SKYBLUE (-4075 1000);
FORCEPROP 1 LAST PART_NUMBER TMP_QCH0106F0B00
J 0
(-4075 900);
DISPLAY 0.489362 (-4075 900);
PAINT SKYBLUE (-4075 900);
FORCEPROP 2 LAST CDS_LIB pure_quanta
J 0
(-4125 1050);
DISPLAY INVISIBLE (-4125 1050);
FORCEPROP 1 LAST PATH I5
J 0
(-4075 1200);
DISPLAY 0.978723 (-4075 1200);
PAINT WHITE (-4075 1200);
DISPLAY INVISIBLE (-4075 1200);
FORCEADD Q_RES..1
(-3625 1450);
FORCEPROP 1 LAST LOCATION R572
J 0
(-3675 1500);
DISPLAY 0.489362 (-3675 1500);
PAINT SKYBLUE (-3675 1500);
FORCEPROP 0 LAST $SEC 1
J 0
(-3675 1625);
DISPLAY 0.680851 (-3675 1625);
PAINT MONO (-3675 1625);
DISPLAY INVISIBLE (-3675 1625);
FORCEPROP 0 LAST CDS_SEC 1
J 0
(-3675 1625);
DISPLAY 1.021277 (-3675 1625);
DISPLAY INVISIBLE (-3675 1625);
FORCEPROP 1 LASTPIN (-3725 1450) $PN 1
J 0
(-3713 1462);
DISPLAY 0.489362 (-3713 1462);
PAINT MONO (-3713 1462);
FORCEPROP 1 LASTPIN (-3525 1450) $PN 2
J 0
(-3563 1462);
DISPLAY 0.489362 (-3563 1462);
PAINT MONO (-3563 1462);
FORCEPROP 1 LAST PART_NUMBER CS62002JB18
J 0
(-3675 1575);
DISPLAY 0.489362 (-3675 1575);
PAINT SKYBLUE (-3675 1575);
FORCEPROP 1 LAST VALUE 20M
J 2
(-3650 1350);
DISPLAY 0.489362 (-3650 1350);
PAINT SKYBLUE (-3650 1350);
FORCEPROP 1 LAST MATERIAL CHIP
J 0
(-3625 1300);
DISPLAY 0.489362 (-3625 1300);
PAINT SKYBLUE (-3625 1300);
FORCEPROP 1 LAST TOLERANCE 5%
J 0
(-3625 1350);
DISPLAY 0.489362 (-3625 1350);
PAINT SKYBLUE (-3625 1350);
FORCEPROP 1 LAST WATTAGE 1/16W
J 2
(-3650 1300);
DISPLAY 0.489362 (-3650 1300);
PAINT SKYBLUE (-3650 1300);
FORCEPROP 1 LAST PACK_TYPE 0402LF
J 0
(-3375 1300);
DISPLAY 0.489362 (-3375 1300);
PAINT SKYBLUE (-3375 1300);
FORCEPROP 1 LAST PATH I6
J 0
(-3675 1600);
DISPLAY 0.978723 (-3675 1600);
PAINT WHITE (-3675 1600);
DISPLAY INVISIBLE (-3675 1600);
FORCEPROP 2 LAST CDS_LIB pure_quanta
J 0
(-3625 1450);
DISPLAY INVISIBLE (-3625 1450);
FORCEADD Q_CRYSTAL..1
(-3625 1750);
FORCEPROP 1 LAST LOCATION Y5
J 0
(-3700 1950);
DISPLAY 0.489362 (-3700 1950);
PAINT SKYBLUE (-3700 1950);
FORCEPROP 0 LAST $SEC 1
J 0
(-3700 2100);
DISPLAY 0.680851 (-3700 2100);
PAINT MONO (-3700 2100);
DISPLAY INVISIBLE (-3700 2100);
FORCEPROP 0 LAST CDS_SEC 1
J 0
(-3700 2100);
DISPLAY 1.021277 (-3700 2100);
DISPLAY INVISIBLE (-3700 2100);
FORCEPROP 0 LASTPIN (-3725 1750) $PN 1
J 2
(-3735 1760);
DISPLAY 0.489362 (-3735 1760);
PAINT MONO (-3735 1760);
FORCEPROP 0 LASTPIN (-3525 1750) $PN 2
J 0
(-3515 1760);
DISPLAY 0.489362 (-3515 1760);
PAINT MONO (-3515 1760);
FORCEPROP 2 LAST PACK_TYPE SMLF
J 0
(-3700 1995);
DISPLAY 0.489362 (-3700 1995);
PAINT SKYBLUE (-3700 1995);
FORCEPROP 1 LAST PART_NUMBER BG632768012
J 0
(-3700 1905);
DISPLAY 0.489362 (-3700 1905);
PAINT SKYBLUE (-3700 1905);
FORCEPROP 2 LAST VALUE 32.768KHZ
J 0
(-3700 2045);
DISPLAY 0.489362 (-3700 2045);
PAINT SKYBLUE (-3700 2045);
FORCEPROP 1 LAST MATERIAL EMPTY
J 0
(-3700 1850);
DISPLAY 0.489362 (-3700 1850);
PAINT RED (-3700 1850);
FORCEPROP 1 LAST PATH I7
J 0
(-3575 1835);
DISPLAY 0.723404 (-3575 1835);
PAINT GREEN (-3575 1835);
DISPLAY INVISIBLE (-3575 1835);
FORCEPROP 1 LAST NEEDS_NO_SIZE TRUE
J 0
(-3625 1750);
DISPLAY 0.468085 (-3625 1750);
PAINT GREEN (-3625 1750);
DISPLAY INVISIBLE (-3625 1750);
FORCEPROP 2 LAST CDS_LIB pure_quanta
J 0
(-3625 1750);
DISPLAY INVISIBLE (-3625 1750);
FORCEADD UNIVERSAL_GND..1
(-3075 675);
FORCEPROP 3 LASTPIN (-3075 725) SIG_NAME GND\g
J 0
(-3065 735);
DISPLAY 0.659574 (-3065 735);
PAINT MONO (-3065 735);
DISPLAY INVISIBLE (-3065 735);
FORCEPROP 1 LAST HDL_POWER GND
J 1
(-3050 600);
DISPLAY 0.872340 (-3050 600);
PAINT GREEN (-3050 600);
DISPLAY INVISIBLE (-3050 600);
FORCEPROP 1 LAST PATH I8
J 0
(-3000 675);
DISPLAY 0.872340 (-3000 675);
PAINT AQUA (-3000 675);
DISPLAY INVISIBLE (-3000 675);
FORCEPROP 2 LAST CDS_LIB pure_quanta_power
J 0
(-3075 675);
DISPLAY INVISIBLE (-3075 675);
FORCEADD Q_CAP..1
(-3075 1075);
FORCEPROP 1 LAST LOCATION C239
J 0
(-3025 1175);
DISPLAY 0.489362 (-3025 1175);
PAINT SKYBLUE (-3025 1175);
FORCEPROP 0 LAST $SEC 1
J 0
(-3025 1225);
DISPLAY 0.680851 (-3025 1225);
PAINT MONO (-3025 1225);
DISPLAY INVISIBLE (-3025 1225);
FORCEPROP 0 LAST CDS_SEC 1
J 0
(-3025 1225);
DISPLAY 1.021277 (-3025 1225);
DISPLAY INVISIBLE (-3025 1225);
FORCEPROP 1 LASTPIN (-3075 1175) $PN 1
J 0
(-3065 1155);
DISPLAY 0.489362 (-3065 1155);
PAINT MONO (-3065 1155);
FORCEPROP 1 LASTPIN (-3075 975) $PN 2
J 0
(-3065 955);
DISPLAY 0.489362 (-3065 955);
PAINT MONO (-3065 955);
FORCEPROP 1 LAST VALUE 10PF
J 0
(-3025 1125);
DISPLAY 0.489362 (-3025 1125);
PAINT SKYBLUE (-3025 1125);
FORCEPROP 1 LAST VOLTAGE 50V
J 0
(-3025 1075);
DISPLAY 0.489362 (-3025 1075);
PAINT SKYBLUE (-3025 1075);
FORCEPROP 1 LAST PACK_TYPE 0402
J 0
(-3025 875);
DISPLAY 0.489362 (-3025 875);
PAINT SKYBLUE (-3025 875);
FORCEPROP 1 LAST MATERIAL NPO
J 0
(-3025 975);
DISPLAY 0.489362 (-3025 975);
PAINT SKYBLUE (-3025 975);
FORCEPROP 1 LAST TOLERANCE 1%
J 0
(-3025 1025);
DISPLAY 0.489362 (-3025 1025);
PAINT SKYBLUE (-3025 1025);
FORCEPROP 1 LAST PART_NUMBER TMP_QCH0106F0B00
J 0
(-3025 925);
DISPLAY 0.489362 (-3025 925);
PAINT SKYBLUE (-3025 925);
FORCEPROP 2 LAST CDS_LIB pure_quanta
J 0
(-3075 1075);
DISPLAY INVISIBLE (-3075 1075);
FORCEPROP 1 LAST PATH I9
J 0
(-3025 1225);
DISPLAY 0.978723 (-3025 1225);
PAINT WHITE (-3025 1225);
DISPLAY INVISIBLE (-3025 1225);
FORCEADD DNS..2
(-8500 2925);
PAINT RED (-8500 2925);
FORCEPROP 2 LAST CDS_LIB mstr_misc
J 0
(-8500 2925);
DISPLAY INVISIBLE (-8500 2925);
FORCEPROP 1 LAST COMMENT_BODY TRUE
J 0
(-8500 2925);
PAINT RED (-8500 2925);
DISPLAY INVISIBLE (-8500 2925);
FORCEADD DNS..2
(-8500 1075);
PAINT RED (-8500 1075);
FORCEPROP 1 LAST COMMENT_BODY TRUE
J 0
(-8500 1075);
DISPLAY 0.744681 (-8500 1075);
DISPLAY INVISIBLE (-8500 1075);
FORCEPROP 2 LAST BOM_COST OCP3.0 
J 0
(-8625 1200);
DISPLAY 0.680851 (-8625 1200);
DISPLAY INVISIBLE (-8625 1200);
FORCEPROP 2 LAST CDS_LIB mstr_misc
J 0
(-8500 1075);
DISPLAY INVISIBLE (-8500 1075);
FORCEADD DNS..2
(-8675 2925);
PAINT RED (-8675 2925);
FORCEPROP 2 LAST CDS_LIB mstr_misc
J 0
(-8675 2925);
DISPLAY INVISIBLE (-8675 2925);
FORCEPROP 1 LAST COMMENT_BODY TRUE
J 0
(-8675 2925);
PAINT RED (-8675 2925);
DISPLAY INVISIBLE (-8675 2925);
FORCEADD DNS..2
(-8850 2925);
PAINT RED (-8850 2925);
FORCEPROP 2 LAST CDS_LIB mstr_misc
J 0
(-8850 2925);
DISPLAY INVISIBLE (-8850 2925);
FORCEPROP 1 LAST COMMENT_BODY TRUE
J 0
(-8850 2925);
PAINT RED (-8850 2925);
DISPLAY INVISIBLE (-8850 2925);
FORCEADD DNS..2
(-8725 1075);
PAINT RED (-8725 1075);
FORCEPROP 1 LAST COMMENT_BODY TRUE
J 0
(-8725 1075);
DISPLAY 0.744681 (-8725 1075);
DISPLAY INVISIBLE (-8725 1075);
FORCEPROP 2 LAST CDS_LIB mstr_misc
J 0
(-8725 1075);
DISPLAY INVISIBLE (-8725 1075);
FORCEPROP 2 LAST BOM_COST OCP3.0 
J 0
(-8850 1200);
DISPLAY 0.680851 (-8850 1200);
DISPLAY INVISIBLE (-8850 1200);
FORCEADD DNS..2
(-8500 350);
PAINT RED (-8500 350);
FORCEPROP 1 LAST COMMENT_BODY TRUE
J 0
(-8500 350);
DISPLAY 0.744681 (-8500 350);
DISPLAY INVISIBLE (-8500 350);
FORCEPROP 2 LAST CDS_LIB mstr_misc
J 0
(-8500 350);
DISPLAY INVISIBLE (-8500 350);
FORCEPROP 2 LAST BOM_COST OCP3.0 
J 0
(-8625 475);
DISPLAY 0.680851 (-8625 475);
DISPLAY INVISIBLE (-8625 475);
FORCEADD DNS..2
(-8725 375);
PAINT RED (-8725 375);
FORCEPROP 1 LAST COMMENT_BODY TRUE
J 0
(-8725 375);
DISPLAY 0.744681 (-8725 375);
DISPLAY INVISIBLE (-8725 375);
FORCEPROP 2 LAST CDS_LIB mstr_misc
J 0
(-8725 375);
DISPLAY INVISIBLE (-8725 375);
FORCEPROP 2 LAST BOM_COST OCP3.0 
J 0
(-8850 500);
DISPLAY 0.680851 (-8850 500);
DISPLAY INVISIBLE (-8850 500);
FORCEADD DNS..2
(-6650 5750);
PAINT RED (-6650 5750);
FORCEPROP 1 LAST COMMENT_BODY TRUE
J 0
(-6650 5750);
PAINT RED (-6650 5750);
DISPLAY INVISIBLE (-6650 5750);
FORCEPROP 2 LAST CDS_LIB mstr_misc
J 0
(-6650 5750);
DISPLAY INVISIBLE (-6650 5750);
FORCEADD DNS..2
(-2225 2125);
PAINT RED (-2225 2125);
FORCEPROP 1 LAST COMMENT_BODY TRUE
R 1
J 0
(-2150 1900);
DISPLAY 0.872340 (-2150 1900);
PAINT GREEN (-2150 1900);
DISPLAY INVISIBLE (-2150 1900);
FORCEPROP 2 LAST CDS_LIB mstr_misc
J 0
(-2225 2125);
DISPLAY INVISIBLE (-2225 2125);
FORCEADD DNS..2
(-8600 1925);
PAINT RED (-8600 1925);
FORCEPROP 1 LAST COMMENT_BODY TRUE
J 0
(-8600 1925);
PAINT RED (-8600 1925);
DISPLAY INVISIBLE (-8600 1925);
FORCEPROP 2 LAST CDS_LIB mstr_misc
J 0
(-8600 1925);
DISPLAY INVISIBLE (-8600 1925);
FORCEADD DNS..2
(-8600 2125);
PAINT RED (-8600 2125);
FORCEPROP 2 LAST CDS_LIB mstr_misc
J 0
(-8600 2125);
DISPLAY INVISIBLE (-8600 2125);
FORCEPROP 1 LAST COMMENT_BODY TRUE
J 0
(-8600 2125);
PAINT RED (-8600 2125);
DISPLAY INVISIBLE (-8600 2125);
FORCEADD DNS..2
(-9025 2925);
PAINT RED (-9025 2925);
FORCEPROP 2 LAST CDS_LIB mstr_misc
J 0
(-9025 2925);
DISPLAY INVISIBLE (-9025 2925);
FORCEPROP 1 LAST COMMENT_BODY TRUE
J 0
(-9025 2925);
PAINT RED (-9025 2925);
DISPLAY INVISIBLE (-9025 2925);
FORCEADD DNS..2
(-3625 1725);
PAINT RED (-3625 1725);
FORCEPROP 1 LAST COMMENT_BODY TRUE
R 1
J 0
(-3550 1500);
DISPLAY 0.872340 (-3550 1500);
PAINT GREEN (-3550 1500);
DISPLAY INVISIBLE (-3550 1500);
FORCEPROP 2 LAST CDS_LIB mstr_misc
J 0
(-3625 1725);
DISPLAY INVISIBLE (-3625 1725);
FORCEADD DNS..2
(-8575 1625);
PAINT RED (-8575 1625);
FORCEPROP 2 LAST CDS_LIB mstr_misc
J 0
(-8575 1625);
DISPLAY INVISIBLE (-8575 1625);
FORCEPROP 1 LAST COMMENT_BODY TRUE
J 0
(-8575 1625);
PAINT RED (-8575 1625);
DISPLAY INVISIBLE (-8575 1625);
FORCEADD QUANTA_TITLE_BLOCK_C..1
(0 0);
FORCEPROP 0 LAST CDS_CON_LAST_MODIFIED Fri Mar 11 14:52:38 2022
J 0
(-1885 15);
DISPLAY INVISIBLE (-1885 15);
FORCEPROP 1 LAST CUSTOM_TXT_CDS <CON_LAST_MODIFIED>
J 0
(-1885 15);
DISPLAY 0.978723 (-1885 15);
FORCEPROP 2 LAST CUSTOM_TXT_CDS <XR_PAGE_TITLE>
J 0
(-7890 5250);
DISPLAY 0.638298 (-7890 5250);
PAINT PINK (-7890 5250);
DISPLAY INVISIBLE (-7890 5250);
FORCEPROP 1 LAST CUSTOM_TXT_CDS <NAME_2>
J 0
(-3175 50);
FORCEPROP 1 LAST CUSTOM_TXT_CDS <NAME_1>
J 0
(-3175 175);
FORCEPROP 1 LAST CUSTOM_TXT_CDS <Q_NUMBER>
J 0
(-1403 103);
DISPLAY 1.212766 (-1403 103);
FORCEPROP 1 LAST CUSTOM_TXT_CDS <Q_PROJ>
J 0
(-2382 102);
DISPLAY 1.212766 (-2382 102);
FORCEPROP 1 LAST CUSTOM_TXT_CDS <Q_REV>
J 0
(-184 103);
DISPLAY 1.212766 (-184 103);
FORCEPROP 1 LAST CUSTOM_TXT_CDS <CON_PAGE_NUM> OF <CON_TOTAL_PAGES>
J 0
(-446 18);
DISPLAY 0.978723 (-446 18);
FORCEPROP 1 LAST Q_TITLE CPU1 MISC 2/2
J 0
(-9275 50);
DISPLAY 2.446809 (-9275 50);
PAINT GREEN (-9275 50);
FORCEPROP 1 LAST Q_DEPT BU9
J 1
(-3763 49);
DISPLAY 1.957447 (-3763 49);
PAINT GREEN (-3763 49);
FORCEPROP 1 LAST COMMENT_BODY TRUE
J 0
(12 -13);
DISPLAY 0.978723 (12 -13);
PAINT GREEN (12 -13);
DISPLAY INVISIBLE (12 -13);
FORCEPROP 2 LAST PAGE_BORDER TRUE
J 0
(-7890 5250);
DISPLAY 0.638298 (-7890 5250);
PAINT PINK (-7890 5250);
DISPLAY INVISIBLE (-7890 5250);
FORCEPROP 1 LAST CDS_LMAN_SYM_OUTLINE -9475,6775,100,-125
J 0
(0 0);
DISPLAY 0.468085 (0 0);
PAINT GREEN (0 0);
DISPLAY INVISIBLE (0 0);
FORCEPROP 2 LAST CDS_LIB pure_quanta
J 0
(0 0);
DISPLAY INVISIBLE (0 0);
FORCEPROP 2 LAST CDS_XR_PAGE_TITLE CR-55 : @T6G_MB_LIB.T6G(SCH_1):PAGE55
J 0
(-7890 5250);
DISPLAY 0.638298 (-7890 5250);
PAINT PINK (-7890 5250);
DISPLAY INVISIBLE (-7890 5250);
WIRE 16 -1 (-5800 1450)(-5900 1450);
WIRE 16 -1 (-5900 1450)(-5900 1300);
FORCEPROP 0 LAST VOLTAGE 0
J 0
(-5900 1125);
PAINT SKYBLUE (-5900 1125);
DISPLAY INVISIBLE (-5900 1125);
FORCEPROP 0 LAST $PHYS_NET_NAME GND
J 0
(-5900 1172);
DISPLAY INVISIBLE (-5900 1172);
WIRE 16 -1 (-5125 1450)(-5125 1300);
WIRE 16 -1 (-5250 1450)(-5125 1450);
WIRE 16 -1 (-4900 725)(-4900 575);
WIRE 16 -1 (-6175 725)(-6175 575);
WIRE 16 -1 (-7150 4875)(-7375 4875);
WIRE 16 -1 (-7375 4875)(-7375 4925);
WIRE 16 -1 (-4125 700)(-4125 950);
WIRE 16 -1 (-3075 725)(-3075 975);
WIRE 16 -1 (-3725 1450)(-4125 1450);
WIRE 16 -1 (-4125 1750)(-4125 1450);
WIRE 16 -1 (-4125 1450)(-4125 1150);
WIRE 16 -1 (-3725 1750)(-4125 1750);
WIRE 16 -1 (-4125 1750)(-4125 2175);
WIRE 16 -1 (-4125 2175)(-2350 2175);
FORCEPROP 2 LAST SIG_NAME XTAL_CPU1_R_X32K_X1
J 0
(-3135 2185);
DISPLAY 0.489362 (-3135 2185);
FORCEPROP 2 LASTPROP $XRERR UNIQUE?
J 0
(-3375 2185);
DISPLAY 0.638298 (-3375 2185);
PAINT MONO (-3375 2185);
DISPLAY INVISIBLE (-3375 2185);
WIRE 16 -1 (-3525 1450)(-3075 1450);
WIRE 16 -1 (-3075 1750)(-3075 1450);
WIRE 16 -1 (-3075 1450)(-3075 1175);
WIRE 16 -1 (-3075 1750)(-3075 2125);
FORCEPROP 2 LAST SIG_NAME XTAL_CPU1_R_X32K_X2
J 0
(-3135 2135);
DISPLAY 0.489362 (-3135 2135);
FORCEPROP 2 LASTPROP $XRERR UNIQUE?
J 0
(-3375 2135);
DISPLAY 0.638298 (-3375 2135);
PAINT MONO (-3375 2135);
DISPLAY INVISIBLE (-3375 2135);
WIRE 16 -1 (-3525 1750)(-3075 1750);
WIRE 16 -1 (-3075 2125)(-2350 2125);
WIRE 16 -1 (-8975 2375)(-8975 2325);
WIRE 16 -1 (-8725 2325)(-8975 2325);
WIRE 16 -1 (-8975 2275)(-8975 2325);
WIRE 16 -1 (-8725 2275)(-8975 2275);
WIRE 16 -1 (-8975 2225)(-8975 2275);
WIRE 16 -1 (-8725 2225)(-8975 2225);
WIRE 16 -1 (-8975 2175)(-8975 2225);
WIRE 16 -1 (-8725 2175)(-8975 2175);
WIRE 16 -1 (-8975 2175)(-8975 2125);
WIRE 16 -1 (-8725 2125)(-8975 2125);
WIRE 16 -1 (-8975 2125)(-8975 2075);
WIRE 16 -1 (-8725 2075)(-8975 2075);
WIRE 16 -1 (-8975 2075)(-8975 2025);
WIRE 16 -1 (-8725 2025)(-8975 2025);
WIRE 16 -1 (-8975 1975)(-8975 2025);
WIRE 16 -1 (-8725 1975)(-8975 1975);
WIRE 16 -1 (-8975 1925)(-8975 1975);
WIRE 16 -1 (-8725 1925)(-8975 1925);
WIRE 16 -1 (-8975 1925)(-8975 1875);
WIRE 16 -1 (-8725 1875)(-8975 1875);
WIRE 16 -1 (-8975 1825)(-8975 1875);
WIRE 16 -1 (-8725 1825)(-8975 1825);
WIRE 16 -1 (-8975 1825)(-8975 1775);
WIRE 16 -1 (-8725 1775)(-8975 1775);
WIRE 16 -1 (-8975 1775)(-8975 1675);
WIRE 16 -1 (-8725 1675)(-8975 1675);
WIRE 16 -1 (-8975 1625)(-8975 1675);
WIRE 16 -1 (-8725 1625)(-8975 1625);
WIRE 16 -1 (-8975 1625)(-8975 1575);
WIRE 16 -1 (-8725 1575)(-8975 1575);
WIRE 16 -1 (-7675 1875)(-8525 1875);
FORCEPROP 2 LAST SIG_NAME CPU1_FORCE_SELFREFRESH
J 0
(-8235 1885);
DISPLAY 0.489362 (-8235 1885);
WIRE 16 -1 (-7675 1925)(-8525 1925);
FORCEPROP 2 LAST SIG_NAME RST_CPU1_RESETL_N
J 0
(-8235 1935);
DISPLAY 0.489362 (-8235 1935);
WIRE 16 -1 (-8525 2025)(-7675 2025);
FORCEPROP 2 LAST SIG_NAME CPU1_SPD_HOST_CTRL_N
J 0
(-8235 2035);
DISPLAY 0.489362 (-8235 2035);
WIRE 16 -1 (-7675 2125)(-8525 2125);
FORCEPROP 2 LAST SIG_NAME PWRGD_CPU1_PWROK
J 0
(-8235 2135);
DISPLAY 0.489362 (-8235 2135);
WIRE 16 -1 (-8525 2175)(-7675 2175);
FORCEPROP 2 LAST SIG_NAME CPU1_FPGA_SPARE3
J 0
(-8235 2185);
DISPLAY 0.489362 (-8235 2185);
WIRE 16 -1 (-7675 1975)(-8525 1975);
FORCEPROP 2 LAST SIG_NAME CPU1_NV_SAVE_N
J 0
(-8235 1985);
DISPLAY 0.489362 (-8235 1985);
WIRE 16 -1 (-8525 2075)(-7675 2075);
FORCEPROP 2 LAST SIG_NAME CPU1_SMERR_N
J 0
(-8235 2085);
DISPLAY 0.489362 (-8235 2085);
WIRE 16 -1 (-8525 2225)(-7675 2225);
FORCEPROP 2 LAST SIG_NAME CPU1_FPGA_SPARE2
J 0
(-8235 2235);
DISPLAY 0.489362 (-8235 2235);
WIRE 16 -1 (-8525 2275)(-7675 2275);
FORCEPROP 2 LAST SIG_NAME CPU1_FPGA_SPARE1
J 0
(-8235 2285);
DISPLAY 0.489362 (-8235 2285);
WIRE 16 -1 (-7675 1825)(-8525 1825);
FORCEPROP 2 LAST SIG_NAME RST_CPU1_SYS_N
J 0
(-8235 1835);
DISPLAY 0.489362 (-8235 1835);
WIRE 16 -1 (-7675 1775)(-8525 1775);
FORCEPROP 2 LAST SIG_NAME CPU1_NMI_SYNC_FLOOD_N
J 0
(-8235 1785);
DISPLAY 0.489362 (-8235 1785);
WIRE 16 -1 (-8525 2325)(-7675 2325);
FORCEPROP 2 LAST SIG_NAME CPU1_FPGA_SPARE0
J 0
(-8235 2335);
DISPLAY 0.489362 (-8235 2335);
WIRE 16 -1 (-9050 3025)(-9050 3075);
WIRE 16 -1 (-8875 3075)(-9050 3075);
WIRE 16 -1 (-8875 3025)(-8875 3075);
WIRE 16 -1 (-8700 3075)(-8875 3075);
WIRE 16 -1 (-8700 3025)(-8700 3075);
WIRE 16 -1 (-8525 3075)(-8700 3075);
WIRE 16 -1 (-8525 3175)(-8525 3075);
WIRE 16 -1 (-8525 3025)(-8525 3075);
WIRE 16 -1 (-8750 1225)(-8525 1225);
WIRE 16 -1 (-8750 1225)(-8750 1250);
WIRE 16 -1 (-8750 1200)(-8750 1225);
WIRE 16 -1 (-8525 1225)(-8525 1200);
WIRE 16 -1 (-9050 2825)(-9050 2600);
WIRE 16 -1 (-7675 2600)(-9050 2600);
FORCEPROP 2 LAST SIG_NAME I3C_1_SPD_DDRGL_CPU1_R_SDA
J 0
(-8235 2610);
DISPLAY 0.489362 (-8235 2610);
WIRE 16 -1 (-8525 2825)(-8525 2750);
WIRE 16 -1 (-8525 2750)(-7675 2750);
FORCEPROP 2 LAST SIG_NAME I3C_0_SPD_DDRAF_CPU1_R_SCL
J 0
(-8235 2760);
DISPLAY 0.489362 (-8235 2760);
WIRE 16 -1 (-8700 2700)(-7675 2700);
FORCEPROP 2 LAST SIG_NAME I3C_0_SPD_DDRAF_CPU1_R_SDA
J 0
(-8235 2710);
DISPLAY 0.489362 (-8235 2710);
WIRE 16 -1 (-8700 2825)(-8700 2700);
WIRE 16 -1 (-8875 2825)(-8875 2650);
WIRE 16 -1 (-7675 2650)(-8875 2650);
FORCEPROP 2 LAST SIG_NAME I3C_1_SPD_DDRGL_CPU1_R_SCL
J 0
(-8235 2660);
DISPLAY 0.489362 (-8235 2660);
WIRE 16 -1 (-7750 550)(-8525 550);
FORCEPROP 2 LAST SIG_NAME RST_CPU1_RSMRST_N
J 0
(-8375 560);
DISPLAY 0.489362 (-8375 560);
WIRE 16 -1 (-8525 1000)(-8525 550);
WIRE 16 -1 (-8525 550)(-8525 475);
WIRE 16 -1 (-6800 4425)(-5625 4425);
FORCEPROP 2 LAST SIG_NAME I3C_0_SPD_DDRAF_CPU1_R_SCL
J 2
(-5785 4435);
DISPLAY 0.489362 (-5785 4435);
WIRE 16 -1 (-8750 475)(-8750 625);
WIRE 16 -1 (-8750 625)(-7750 625);
FORCEPROP 2 LAST SIG_NAME CPU1_PWRGD_OUT
J 0
(-8375 635);
DISPLAY 0.489362 (-8375 635);
WIRE 16 -1 (-8750 625)(-8750 1000);
WIRE 16 -1 (-8525 1625)(-7675 1625);
FORCEPROP 2 LAST SIG_NAME CPU1_SLP_S5_N
J 0
(-8235 1635);
DISPLAY 0.489362 (-8235 1635);
WIRE 16 -1 (-8525 1575)(-7675 1575);
FORCEPROP 2 LAST SIG_NAME CPU1_SLP_S3_N
J 0
(-8235 1585);
DISPLAY 0.489362 (-8235 1585);
WIRE 16 -1 (-7675 1675)(-8525 1675);
FORCEPROP 2 LAST SIG_NAME CPU1_PWRGD_OUT
J 0
(-8235 1685);
DISPLAY 0.489362 (-8235 1685);
WIRE 16 -1 (-7000 3475)(-7850 3475);
FORCEPROP 2 LAST SIG_NAME CPU1_SPD_HOST_CTRL_N
J 2
(-7310 3485);
DISPLAY 0.489362 (-7310 3485);
WIRE 16 -1 (-6800 3475)(-5625 3475);
FORCEPROP 2 LAST SIG_NAME CPU1_SPD_HOST_CTRL_R_N
J 2
(-6135 3485);
DISPLAY 0.489362 (-6135 3485);
FORCEPROP 2 LASTPROP $XRERR UNIQUE?
J 0
(-6375 3485);
DISPLAY 0.638298 (-6375 3485);
PAINT MONO (-6375 3485);
DISPLAY INVISIBLE (-6375 3485);
WIRE 16 -1 (-5625 1050)(-6175 1050);
WIRE 16 -1 (-6175 1650)(-6175 1050);
WIRE 16 -1 (-6175 1050)(-6175 925);
WIRE 16 -1 (-5800 1650)(-6175 1650);
WIRE 16 -1 (-6175 1650)(-6175 2150);
WIRE 16 -1 (-6175 2150)(-4550 2150);
FORCEPROP 2 LAST SIG_NAME XTAL_CPU1_X48M_X1
J 0
(-4960 2160);
DISPLAY 0.489362 (-4960 2160);
WIRE 16 -1 (-6375 3725)(-5625 3725);
FORCEPROP 2 LAST SIG_NAME CPU1_SMERR_N
J 0
(-6325 3735);
DISPLAY 0.489362 (-6325 3735);
WIRE 16 -1 (-6600 3375)(-5625 3375);
FORCEPROP 2 LAST SIG_NAME CPU1_FPGA_SPARE0
J 0
(-6575 3385);
DISPLAY 0.489362 (-6575 3385);
WIRE 16 -1 (-6600 3325)(-5625 3325);
FORCEPROP 2 LAST SIG_NAME CPU1_FPGA_SPARE1
J 0
(-6575 3335);
DISPLAY 0.489362 (-6575 3335);
WIRE 16 -1 (-6600 3275)(-5625 3275);
FORCEPROP 2 LAST SIG_NAME CPU1_FPGA_SPARE2
J 0
(-6575 3285);
DISPLAY 0.489362 (-6575 3285);
WIRE 16 -1 (-6600 3225)(-5625 3225);
FORCEPROP 2 LAST SIG_NAME CPU1_FPGA_SPARE3
J 0
(-6575 3235);
DISPLAY 0.489362 (-6575 3235);
WIRE 16 -1 (-6650 3175)(-5625 3175);
FORCEPROP 2 LAST SIG_NAME SLOT2_BUF_SKU_ID0
J 0
(-6575 3185);
DISPLAY 0.489362 (-6575 3185);
WIRE 16 -1 (-6650 3125)(-5625 3125);
FORCEPROP 2 LAST SIG_NAME SLOT2_BUF_SKU_ID1
J 0
(-6575 3135);
DISPLAY 0.489362 (-6575 3135);
WIRE 16 -1 (-5425 1050)(-4900 1050);
WIRE 16 -1 (-4900 1650)(-4900 1050);
WIRE 16 -1 (-4900 1050)(-4900 925);
WIRE 16 -1 (-5250 1650)(-4900 1650);
WIRE 16 -1 (-4900 1650)(-4900 2100);
FORCEPROP 2 LAST SIG_NAME XTAL_CPU1_X48M_X2
J 0
(-4960 2110);
DISPLAY 0.489362 (-4960 2110);
WIRE 16 -1 (-4900 2100)(-4550 2100);
WIRE 16 -1 (-6725 5775)(-7575 5775);
FORCEPROP 2 LAST SIG_NAME FM_CPU1_SLP_S5_N
J 0
(-7425 5785);
DISPLAY 0.489362 (-7425 5785);
WIRE 16 -1 (-6725 5725)(-7575 5725);
FORCEPROP 2 LAST SIG_NAME FM_CPU1_SLP_S3_N
J 0
(-7425 5735);
DISPLAY 0.489362 (-7425 5735);
WIRE 16 -1 (-5625 5775)(-6525 5775);
FORCEPROP 2 LAST SIG_NAME CPU1_SLP_S5_N
J 0
(-6350 5785);
DISPLAY 0.489362 (-6350 5785);
FORCEPROP 2 LASTPROP $XR0 55 
J 0
(-6620 5785);
DISPLAY 0.638298 (-6620 5785);
PAINT MONO (-6620 5785);
WIRE 16 -1 (-5625 5725)(-6525 5725);
FORCEPROP 2 LAST SIG_NAME CPU1_SLP_S3_N
J 0
(-6350 5735);
DISPLAY 0.489362 (-6350 5735);
FORCEPROP 2 LASTPROP $XR0 55 
J 0
(-6620 5735);
DISPLAY 0.638298 (-6620 5735);
PAINT MONO (-6620 5735);
WIRE 16 -1 (-6950 4875)(-5625 4875);
FORCEPROP 2 LAST SIG_NAME INT_CPU1_HP_UBM_N
J 0
(-6325 4885);
DISPLAY 0.489362 (-6325 4885);
FORCEPROP 2 LASTPROP $XRERR UNIQUE?
J 0
(-6565 4885);
DISPLAY 0.638298 (-6565 4885);
PAINT MONO (-6565 4885);
DISPLAY INVISIBLE (-6565 4885);
WIRE 16 -1 (-5625 5625)(-6375 5625);
FORCEPROP 2 LAST SIG_NAME NC_CPU1_PWR_BTN_N
J 0
(-6325 5635);
DISPLAY 0.489362 (-6325 5635);
FORCEPROP 2 LASTPROP $XRERR UNIQUE?
J 0
(-6615 5625);
DISPLAY 0.638298 (-6615 5625);
PAINT MONO (-6615 5625);
DISPLAY INVISIBLE (-6615 5625);
WIRE 16 -1 (-6375 5525)(-5625 5525);
FORCEPROP 2 LAST SIG_NAME RST_CPU1_RSMRST_N
J 2
(-5935 5535);
DISPLAY 0.489362 (-5935 5535);
WIRE 16 -1 (-6375 5425)(-5625 5425);
FORCEPROP 2 LAST SIG_NAME CPU1_PWR_GD_IN
J 0
(-6310 5435);
DISPLAY 0.489362 (-6310 5435);
WIRE 16 -1 (-6375 5575)(-5625 5575);
FORCEPROP 2 LAST SIG_NAME RST_CPU1_SYS_N
J 2
(-6010 5585);
DISPLAY 0.489362 (-6010 5585);
WIRE 16 -1 (-6375 5225)(-5625 5225);
FORCEPROP 2 LAST SIG_NAME XTAL_CPU1_X48M_X2
J 0
(-6325 5235);
DISPLAY 0.489362 (-6325 5235);
WIRE 16 -1 (-6375 5275)(-5625 5275);
FORCEPROP 2 LAST SIG_NAME XTAL_CPU1_X48M_X1
J 0
(-6325 5285);
DISPLAY 0.489362 (-6325 5285);
WIRE 16 -1 (-6375 4675)(-5625 4675);
FORCEPROP 2 LAST SIG_NAME CPU1_NMI_SYNC_FLOOD_N
J 0
(-6325 4685);
DISPLAY 0.489362 (-6325 4685);
WIRE 16 -1 (-6375 5025)(-5625 5025);
FORCEPROP 2 LAST SIG_NAME XTAL_CPU1_X32K_X2
J 0
(-6325 5035);
DISPLAY 0.489362 (-6325 5035);
WIRE 16 -1 (-6375 5075)(-5625 5075);
FORCEPROP 2 LAST SIG_NAME XTAL_CPU1_X32K_X1
J 0
(-6325 5085);
DISPLAY 0.489362 (-6325 5085);
WIRE 16 -1 (-6800 4375)(-5625 4375);
FORCEPROP 2 LAST SIG_NAME I3C_0_SPD_DDRAF_CPU1_R_SDA
J 2
(-5785 4385);
DISPLAY 0.489362 (-5785 4385);
WIRE 16 -1 (-6800 4325)(-5625 4325);
FORCEPROP 2 LAST SIG_NAME I3C_1_SPD_DDRGL_CPU1_R_SCL
J 2
(-5785 4335);
DISPLAY 0.489362 (-5785 4335);
WIRE 16 -1 (-6800 4275)(-5625 4275);
FORCEPROP 2 LAST SIG_NAME I3C_1_SPD_DDRGL_CPU1_R_SDA
J 2
(-5785 4285);
DISPLAY 0.489362 (-5785 4285);
WIRE 16 -1 (-3125 3875)(-2225 3875);
FORCEPROP 2 LAST SIG_NAME CLK_100M_CPU1_CLK13_R_DP
J 0
(-2985 3885);
DISPLAY 0.489362 (-2985 3885);
FORCEPROP 2 LASTPROP $XRERR UNIQUE?
J 0
(-3225 3885);
DISPLAY 0.638298 (-3225 3885);
PAINT MONO (-3225 3885);
DISPLAY INVISIBLE (-3225 3885);
WIRE 16 -1 (-3125 3825)(-2225 3825);
FORCEPROP 2 LAST SIG_NAME CLK_100M_CPU1_CLK13_R_DN
J 0
(-2985 3835);
DISPLAY 0.489362 (-2985 3835);
FORCEPROP 2 LASTPROP $XRERR UNIQUE?
J 0
(-3225 3835);
DISPLAY 0.638298 (-3225 3835);
PAINT MONO (-3225 3835);
DISPLAY INVISIBLE (-3225 3835);
WIRE 16 -1 (-3125 3575)(-2225 3575);
FORCEPROP 2 LAST SIG_NAME CLK_100M_CPU1_CLK15_R_DP
J 0
(-2985 3585);
DISPLAY 0.489362 (-2985 3585);
FORCEPROP 2 LASTPROP $XRERR UNIQUE?
J 0
(-3225 3585);
DISPLAY 0.638298 (-3225 3585);
PAINT MONO (-3225 3585);
DISPLAY INVISIBLE (-3225 3585);
WIRE 16 -1 (-3125 3525)(-2225 3525);
FORCEPROP 2 LAST SIG_NAME CLK_100M_CPU1_CLK15_R_DN
J 0
(-2985 3535);
DISPLAY 0.489362 (-2985 3535);
FORCEPROP 2 LASTPROP $XRERR UNIQUE?
J 0
(-3225 3535);
DISPLAY 0.638298 (-3225 3535);
PAINT MONO (-3225 3535);
DISPLAY INVISIBLE (-3225 3535);
WIRE 16 -1 (-3125 3125)(-2200 3125);
FORCEPROP 2 LAST SIG_NAME SMB_CPU1_SEC_SDA
J 2
(-2375 3135);
DISPLAY 0.489362 (-2375 3135);
WIRE 16 -1 (-3125 3175)(-2200 3175);
FORCEPROP 2 LAST SIG_NAME SMB_CPU1_SEC_SCL
J 2
(-2375 3185);
DISPLAY 0.489362 (-2375 3185);
WIRE 16 -1 (-2350 2425)(-3075 2425);
FORCEPROP 2 LAST SIG_NAME CLK_CPU0_RTCCLK
J 0
(-2985 2435);
DISPLAY 0.489362 (-2985 2435);
WIRE 16 -1 (-2150 2125)(-1200 2125);
FORCEPROP 2 LAST SIG_NAME XTAL_CPU1_X32K_X2
J 0
(-1660 2135);
DISPLAY 0.489362 (-1660 2135);
WIRE 16 -1 (-1925 2175)(-1925 2425);
WIRE 16 -1 (-2150 2175)(-1925 2175);
WIRE 16 -1 (-1925 2175)(-1200 2175);
FORCEPROP 2 LAST SIG_NAME XTAL_CPU1_X32K_X1
J 0
(-1660 2185);
DISPLAY 0.489362 (-1660 2185);
WIRE 16 -1 (-1925 2425)(-2150 2425);
WIRE 16 -1 (-2025 3875)(-1200 3875);
FORCEPROP 2 LAST SIG_NAME CLK_100M_CPU1_CLK13_DP
J 0
(-1835 3885);
DISPLAY 0.489362 (-1835 3885);
WIRE 16 -1 (-2025 3825)(-1200 3825);
FORCEPROP 2 LAST SIG_NAME CLK_100M_CPU1_CLK13_DN
J 0
(-1835 3835);
DISPLAY 0.489362 (-1835 3835);
WIRE 16 -1 (-2025 3575)(-1200 3575);
FORCEPROP 2 LAST SIG_NAME CLK_100M_CPU1_CLK15_DP
J 0
(-1835 3585);
DISPLAY 0.489362 (-1835 3585);
WIRE 16 -1 (-2025 3525)(-1200 3525);
FORCEPROP 2 LAST SIG_NAME CLK_100M_CPU1_CLK15_DN
J 0
(-1835 3535);
DISPLAY 0.489362 (-1835 3535);
WIRE 16 -1 (-3125 4125)(-2225 4125);
FORCEPROP 2 LAST SIG_NAME CLK_100M_CPU1_CLK11_R_DN
J 0
(-2985 4135);
DISPLAY 0.489362 (-2985 4135);
FORCEPROP 2 LASTPROP $XRERR UNIQUE?
J 0
(-3225 4135);
DISPLAY 0.638298 (-3225 4135);
PAINT MONO (-3225 4135);
DISPLAY INVISIBLE (-3225 4135);
WIRE 16 -1 (-3125 4175)(-2225 4175);
FORCEPROP 2 LAST SIG_NAME CLK_100M_CPU1_CLK11_R_DP
J 0
(-2985 4185);
DISPLAY 0.489362 (-2985 4185);
FORCEPROP 2 LASTPROP $XRERR UNIQUE?
J 0
(-3225 4185);
DISPLAY 0.638298 (-3225 4185);
PAINT MONO (-3225 4185);
DISPLAY INVISIBLE (-3225 4185);
WIRE 16 -1 (-3125 6125)(-2350 6125);
FORCEPROP 2 LAST SIG_NAME CLK_100M_REF_IN_DP
J 0
(-2900 6135);
DISPLAY 0.489362 (-2900 6135);
WIRE 16 -1 (-3125 6075)(-2350 6075);
FORCEPROP 2 LAST SIG_NAME CLK_100M_REF_IN_DN
J 0
(-2900 6085);
DISPLAY 0.489362 (-2900 6085);
WIRE 16 -1 (-3125 5775)(-2225 5775);
FORCEPROP 2 LAST SIG_NAME PWRGD_CPU1_PWROK
J 0
(-2910 5785);
DISPLAY 0.489362 (-2910 5785);
WIRE 16 -1 (-3125 5875)(-2225 5875);
FORCEPROP 2 LAST SIG_NAME RST_CPU1_RESETL_N
J 0
(-2900 5885);
DISPLAY 0.489362 (-2900 5885);
WIRE 16 -1 (-3125 5425)(-2350 5425);
FORCEPROP 2 LAST SIG_NAME CPU1_FORCE_SELFREFRESH
J 0
(-2885 5435);
DISPLAY 0.489362 (-2885 5435);
WIRE 16 -1 (-3125 5625)(-2350 5625);
FORCEPROP 2 LAST SIG_NAME CPU1_PWRGD_OUT
J 0
(-2900 5635);
DISPLAY 0.489362 (-2900 5635);
WIRE 16 -1 (-3125 5325)(-2350 5325);
FORCEPROP 2 LAST SIG_NAME CPU1_NV_SAVE_N
J 0
(-2900 5335);
DISPLAY 0.489362 (-2900 5335);
WIRE 16 -1 (-3125 5175)(-2325 5175);
FORCEPROP 2 LAST SIG_NAME RST_CPU1_PERST0_N
J 0
(-2860 5185);
DISPLAY 0.489362 (-2860 5185);
WIRE 16 -1 (-3125 5125)(-2325 5125);
FORCEPROP 2 LAST SIG_NAME RST_CPU1_PERST1_N
J 0
(-2860 5135);
DISPLAY 0.489362 (-2860 5135);
WIRE 16 -1 (-2225 5975)(-3125 5975);
FORCEPROP 2 LAST SIG_NAME CLK_CPU1_RTCCLK
J 0
(-2900 5985);
DISPLAY 0.489362 (-2900 5985);
WIRE 16 -1 (-3125 5525)(-1050 5525);
FORCEPROP 2 LAST SIG_NAME IRQ_WAKE_N
J 0
(-2910 5535);
DISPLAY 0.489362 (-2910 5535);
WIRE 16 -1 (-2025 4175)(-1200 4175);
FORCEPROP 2 LAST SIG_NAME CLK_100M_CPU1_CLK11_DP
J 0
(-1835 4185);
DISPLAY 0.489362 (-1835 4185);
WIRE 16 -1 (-2025 4125)(-1200 4125);
FORCEPROP 2 LAST SIG_NAME CLK_100M_CPU1_CLK11_DN
J 0
(-1835 4135);
DISPLAY 0.489362 (-1835 4135);
DOT 1 (-8875 3075);
DOT 1 (-8975 1925);
DOT 1 (-1925 2175);
DOT 1 (-8975 2275);
DOT 1 (-8975 2325);
DOT 1 (-8700 3075);
DOT 1 (-3075 1750);
DOT 1 (-3075 1450);
DOT 1 (-6175 1650);
DOT 1 (-6175 1050);
DOT 1 (-4125 1750);
DOT 1 (-4125 1450);
DOT 1 (-4900 1050);
DOT 1 (-4900 1650);
DOT 1 (-8525 550);
DOT 1 (-8525 3075);
DOT 1 (-8975 1625);
DOT 1 (-8750 1225);
DOT 1 (-8750 625);
DOT 1 (-8975 2225);
DOT 1 (-8975 2025);
DOT 1 (-8975 2175);
DOT 1 (-8975 2125);
DOT 1 (-8975 1675);
DOT 1 (-8975 1825);
DOT 1 (-8975 1775);
DOT 1 (-8975 1875);
DOT 1 (-8975 2075);
DOT 1 (-8975 1975);
QUIT
